G04 ================== begin FILE IDENTIFICATION RECORD ==================*
G04 Layout Name:  DAT6MTH3AD0_t6m_cm_d_brd_103112_274.brd*
G04 Film Name:    vcc2*
G04 File Format:  Gerber RS274X*
G04 File Origin:  Cadence Allegro 16.3-S048*
G04 Origin Date:  Tue Nov 26 10:18:26 2013*
G04 *
G04 Layer:  VIA CLASS/VCC2*
G04 Layer:  PIN/VCC2*
G04 Layer:  MANUFACTURING/PHOTOPLOT_OUTLINE*
G04 Layer:  ETCH/VCC2*
G04 Layer:  DRAWING FORMAT/TITLE_BLOCK*
G04 Layer:  DRAWING FORMAT/TITLE_DATA_VCC1*
G04 *
G04 Offset:    (0.00 0.00)*
G04 Mirror:    No*
G04 Mode:      Negative*
G04 Rotation:  0*
G04 FullContactRelief:  No*
G04 UndefLineWidth:     6.00*
G04 ================== end FILE IDENTIFICATION RECORD ====================*
%FSLAX25Y25*MOIN*%
%IR0*IPPOS*OFA0.00000B0.00000*MIA0B0*SFA1.00000B1.00000*%
%ADD10C,.03*%
%ADD32C,.042*%
%ADD16C,.06*%
%ADD38C,.061*%
%ADD21O,.058X.154*%
%ADD28C,.026*%
%ADD19C,.053*%
%ADD11C,.08*%
%ADD31C,.072*%
%ADD43C,.046*%
%ADD36C,.064*%
%ADD40C,.056*%
%ADD37C,.066*%
%ADD33C,.076*%
%AMMACRO29*
4,1,36,0.0,.004,
.000695,.003939,
.001368,.003759,
.002,.003464,
.002571,.003064,
.003064,.002571,
.003464,.002,
.003759,.001368,
.003939,.000695,
.004,0.0,
.003939,-.000695,
.003759,-.001368,
.003464,-.002,
.003064,-.002571,
.002571,-.003064,
.002,-.003464,
.001368,-.003759,
.000695,-.003939,
0.0,-.004,
-.000695,-.003939,
-.001368,-.003759,
-.002,-.003464,
-.002571,-.003064,
-.003064,-.002571,
-.003464,-.002,
-.003759,-.001368,
-.003939,-.000695,
-.004,0.0,
-.003939,.000695,
-.003759,.001368,
-.003464,.002,
-.003064,.002571,
-.002571,.003064,
-.002,.003464,
-.001368,.003759,
-.000695,.003939,
0.0,.004,
180.*
%
%ADD29MACRO29*%
%AMMACRO24*
4,1,36,0.0,.004,
.000695,.003939,
.001368,.003759,
.002,.003464,
.002571,.003064,
.003064,.002571,
.003464,.002,
.003759,.001368,
.003939,.000695,
.004,0.0,
.003939,-.000695,
.003759,-.001368,
.003464,-.002,
.003064,-.002571,
.002571,-.003064,
.002,-.003464,
.001368,-.003759,
.000695,-.003939,
0.0,-.004,
-.000695,-.003939,
-.001368,-.003759,
-.002,-.003464,
-.002571,-.003064,
-.003064,-.002571,
-.003464,-.002,
-.003759,-.001368,
-.003939,-.000695,
-.004,0.0,
-.003939,.000695,
-.003759,.001368,
-.003464,.002,
-.003064,.002571,
-.002571,.003064,
-.002,.003464,
-.001368,.003759,
-.000695,.003939,
0.0,.004,
270.*
%
%ADD24MACRO24*%
%ADD27C,.095*%
%ADD23C,.068*%
%ADD18C,.077*%
%ADD22C,.089*%
%AMMACRO41*
4,1,15,.02291,.0123,
.024698,.008135,
.025735,.003723,
.025991,-.000803,
.025456,-.005304,
.024149,-.009644,
.02291,-.0123,
.02803,-.01742,
.030629,-.012288,
.032298,-.006783,
.032985,-.001071,
.03267,.004673,
.031362,.010275,
.029101,.015565,
.02803,.01742,
.02291,.0123,
90.*
4,1,15,.0123,-.02291,
.008135,-.024698,
.003723,-.025735,
-.000803,-.025991,
-.005304,-.025456,
-.009644,-.024149,
-.0123,-.02291,
-.01742,-.02803,
-.012288,-.030629,
-.006783,-.032298,
-.001071,-.032985,
.004673,-.03267,
.010275,-.031362,
.015565,-.029101,
.01742,-.02803,
.0123,-.02291,
90.*
4,1,15,-.02291,-.0123,
-.024698,-.008135,
-.025735,-.003723,
-.025991,.000803,
-.025456,.005304,
-.024149,.009644,
-.02291,.0123,
-.02803,.01742,
-.030629,.012288,
-.032298,.006783,
-.032985,.001071,
-.03267,-.004673,
-.031362,-.010275,
-.029101,-.015565,
-.02803,-.01742,
-.02291,-.0123,
90.*
4,1,15,-.0123,.02291,
-.008135,.024698,
-.003723,.025735,
.000803,.025991,
.005304,.025456,
.009644,.024149,
.0123,.02291,
.01742,.02803,
.012288,.030629,
.006783,.032298,
.001071,.032985,
-.004673,.03267,
-.010275,.031362,
-.015565,.029101,
-.01742,.02803,
-.0123,.02291,
90.*
%
%ADD41MACRO41*%
%ADD45C,.11*%
%ADD17C,.15*%
%ADD35C,.233*%
%ADD44C,.18*%
%ADD25C,.172*%
%ADD26C,.148*%
%ADD34C,.188*%
%AMMACRO20*
4,1,36,0.0,.004,
.000695,.003939,
.001368,.003759,
.002,.003464,
.002571,.003064,
.003064,.002571,
.003464,.002,
.003759,.001368,
.003939,.000695,
.004,0.0,
.003939,-.000695,
.003759,-.001368,
.003464,-.002,
.003064,-.002571,
.002571,-.003064,
.002,-.003464,
.001368,-.003759,
.000695,-.003939,
0.0,-.004,
-.000695,-.003939,
-.001368,-.003759,
-.002,-.003464,
-.002571,-.003064,
-.003064,-.002571,
-.003464,-.002,
-.003759,-.001368,
-.003939,-.000695,
-.004,0.0,
-.003939,.000695,
-.003759,.001368,
-.003464,.002,
-.003064,.002571,
-.002571,.003064,
-.002,.003464,
-.001368,.003759,
-.000695,.003939,
0.0,.004,
90.*
%
%ADD20MACRO20*%
%AMMACRO14*
4,1,36,0.0,.004,
.000695,.003939,
.001368,.003759,
.002,.003464,
.002571,.003064,
.003064,.002571,
.003464,.002,
.003759,.001368,
.003939,.000695,
.004,0.0,
.003939,-.000695,
.003759,-.001368,
.003464,-.002,
.003064,-.002571,
.002571,-.003064,
.002,-.003464,
.001368,-.003759,
.000695,-.003939,
0.0,-.004,
-.000695,-.003939,
-.001368,-.003759,
-.002,-.003464,
-.002571,-.003064,
-.003064,-.002571,
-.003464,-.002,
-.003759,-.001368,
-.003939,-.000695,
-.004,0.0,
-.003939,.000695,
-.003759,.001368,
-.003464,.002,
-.003064,.002571,
-.002571,.003064,
-.002,.003464,
-.001368,.003759,
-.000695,.003939,
0.0,.004,
0.0*
%
%ADD14MACRO14*%
%AMMACRO30*
4,1,36,0.0,.004,
.000695,.003939,
.001368,.003759,
.002,.003464,
.002571,.003064,
.003064,.002571,
.003464,.002,
.003759,.001368,
.003939,.000695,
.004,0.0,
.003939,-.000695,
.003759,-.001368,
.003464,-.002,
.003064,-.002571,
.002571,-.003064,
.002,-.003464,
.001368,-.003759,
.000695,-.003939,
0.0,-.004,
-.000695,-.003939,
-.001368,-.003759,
-.002,-.003464,
-.002571,-.003064,
-.003064,-.002571,
-.003464,-.002,
-.003759,-.001368,
-.003939,-.000695,
-.004,0.0,
-.003939,.000695,
-.003759,.001368,
-.003464,.002,
-.003064,.002571,
-.002571,.003064,
-.002,.003464,
-.001368,.003759,
-.000695,.003939,
0.0,.004,
.001*
%
%ADD30MACRO30*%
%AMMACRO39*
4,1,15,.02475,.01414,
.026829,.009627,
.028094,.004822,
.028504,-.000129,
.028049,-.005077,
.026741,-.009871,
.02475,-.01414,
.02984,-.01923,
.032726,-.013756,
.034617,-.007864,
.035457,-.001734,
.03522,.00445,
.033912,.010498,
.031574,.016227,
.02984,.01923,
.02475,.01414,
180.*
4,1,15,.01414,-.02475,
.009627,-.026829,
.004822,-.028094,
-.000129,-.028504,
-.005077,-.028049,
-.009871,-.026741,
-.01414,-.02475,
-.01923,-.02984,
-.013756,-.032726,
-.007864,-.034617,
-.001734,-.035457,
.00445,-.03522,
.010498,-.033912,
.016227,-.031574,
.01923,-.02984,
.01414,-.02475,
180.*
4,1,15,-.02475,-.01414,
-.026829,-.009627,
-.028094,-.004822,
-.028504,.000129,
-.028049,.005077,
-.026741,.009871,
-.02475,.01414,
-.02984,.01923,
-.032726,.013756,
-.034617,.007864,
-.035457,.001734,
-.03522,-.00445,
-.033912,-.010498,
-.031574,-.016227,
-.02984,-.01923,
-.02475,-.01414,
180.*
4,1,15,-.01414,.02475,
-.009627,.026829,
-.004822,.028094,
.000129,.028504,
.005077,.028049,
.009871,.026741,
.01414,.02475,
.01923,.02984,
.013756,.032726,
.007864,.034617,
.001734,.035457,
-.00445,.03522,
-.010498,.033912,
-.016227,.031574,
-.01923,.02984,
-.01414,.02475,
180.*
%
%ADD39MACRO39*%
%AMMACRO42*
4,1,16,.02657,.01597,
.02894,.011114,
.03043,.005919,
.030995,.000545,
.030619,-.004845,
.029313,-.010088,
.027115,-.015025,
.02657,-.01597,
.03164,-.02104,
.034813,-.015226,
.036928,-.00895,
.037921,-.002401,
.037762,.00422,
.036455,.010713,
.034041,.016881,
.03164,.02104,
.02657,.01597,
270.*
4,1,16,.01597,-.02657,
.011114,-.02894,
.005919,-.03043,
.000545,-.030995,
-.004845,-.030619,
-.010088,-.029313,
-.015025,-.027115,
-.01597,-.02657,
-.02104,-.03164,
-.015226,-.034813,
-.00895,-.036928,
-.002401,-.037921,
.00422,-.037762,
.010713,-.036455,
.016881,-.034041,
.02104,-.03164,
.01597,-.02657,
270.*
4,1,16,-.02657,-.01597,
-.02894,-.011114,
-.03043,-.005919,
-.030995,-.000545,
-.030619,.004845,
-.029313,.010088,
-.027115,.015025,
-.02657,.01597,
-.03164,.02104,
-.034813,.015226,
-.036928,.00895,
-.037921,.002401,
-.037762,-.00422,
-.036455,-.010713,
-.034041,-.016881,
-.03164,-.02104,
-.02657,-.01597,
270.*
4,1,16,-.01597,.02657,
-.011114,.02894,
-.005919,.03043,
-.000545,.030995,
.004845,.030619,
.010088,.029313,
.015025,.027115,
.01597,.02657,
.02104,.03164,
.015226,.034813,
.00895,.036928,
.002401,.037921,
-.00422,.037762,
-.010713,.036455,
-.016881,.034041,
-.02104,.03164,
-.01597,.02657,
270.*
%
%ADD42MACRO42*%
%ADD46C,.006*%
%ADD47C,.07006*%
%ADD51C,.09107*%
%ADD50C,.0971*%
%ADD49C,.07807*%
%ADD48C,.07907*%
%ADD52C,.15206*%
%ADD53C,.15806*%
G75*
%LPD*%
G75*
G36*
G01X-1043962Y-705877D02*
X2300638D01*
Y2342823D01*
X-1043962D01*
Y-705877D01*
G37*
%LPC*%
G75*
G36*
G01X-67803Y813780D02*
G02X-63929Y817654I3874J0D01*
G01X-12373D01*
G02X-11873Y817154I0J-500D01*
G01Y635398D01*
X-11874D01*
Y4500D01*
G02X-12374Y4000I-500J0D01*
G01X-63929D01*
G02X-67803Y7874I0J3874D01*
G01Y813780D01*
G37*
G36*
G01X683244Y793925D02*
G02X682938Y793465I-500J1D01*
G03X683159Y790622I582J-1385D01*
G02X683521Y790269I-120J-485D01*
G03X698724Y792323I7463J2053D01*
G01Y817152D01*
G02X699224Y817652I500J0D01*
G01X734319D01*
G02X734819Y817152I0J-500D01*
G01Y679921D01*
G03X746693Y668047I11874J0D01*
G01X779528D01*
G02X783402Y664173I0J-3874D01*
G01Y297835D01*
G02X781496Y295929I-1906J0D01*
G01X780315D01*
G03X770409Y286024I0J-9906D01*
G01Y132480D01*
G03X780315Y122575I9906J1D01*
G01X781496D01*
G02X783402Y120669I0J-1906D01*
G01Y7874D01*
G02X779528Y4000I-3874J0D01*
G01X7874D01*
G02X4000Y7874I0J3874D01*
G01Y115354D01*
G02X5906Y117260I1906J0D01*
G01X25591D01*
G03X35496Y127165I0J9905D01*
G01Y272835D01*
G03X25591Y282740I-9905J0D01*
G01X5906D01*
G02X4000Y284646I0J1906D01*
G01Y664173D01*
G02X7874Y668047I3874J0D01*
G01X40787D01*
G03X52661Y679921I0J11874D01*
G01Y817152D01*
G02X53161Y817652I500J0D01*
G01X324476D01*
G02X324976Y817152I0J-500D01*
G01Y792323D01*
G03X340457I7740J0D01*
G01Y817152D01*
G02X340957Y817652I500J0D01*
G01X376051D01*
G02X376551Y817152I0J-500D01*
G01Y793222D01*
X376404Y792982D01*
X376278Y792918D01*
G03X375758Y790680I682J-1338D01*
G02Y789480I-800J-600D01*
G03X376278Y787242I1202J-900D01*
G01X376404Y787178D01*
X376551Y786938D01*
Y741142D01*
G03X379709Y731213I17188J0D01*
G02X378893Y729635I-816J-578D01*
G01X355917D01*
G02X355568Y729777I0J500D01*
G03X353472I-1048J-1076D01*
G02X353123Y729635I-349J358D01*
G01X253469D01*
X249940Y726106D01*
G02X249382Y726003I-354J353D01*
G03X247398Y724019I-612J-1372D01*
G02X247295Y723461I-456J-204D01*
G01X237616Y713782D01*
X237565Y713751D01*
G03X237066Y713252I783J-1282D01*
G01X237035Y713201D01*
X229335Y705501D01*
Y673240D01*
X229210Y673015D01*
X229100Y672946D01*
G03Y670398I795J-1274D01*
G02X229335Y669974I-265J-424D01*
G01Y654525D01*
G02X229022Y654061I-500J0D01*
G03Y651275I562J-1393D01*
G02X229335Y650811I-187J-464D01*
G01Y641795D01*
X232946Y638184D01*
X233021Y637970D01*
X233008Y637855D01*
G03X234670Y636193I1492J-170D01*
G02X235081Y636049I57J-497D01*
G01X239190Y631940D01*
X242013D01*
X242260Y631779D01*
X242321Y631643D01*
G03X245065I1372J611D01*
G01X245126Y631779D01*
X245373Y631940D01*
X263315D01*
X266156Y634781D01*
Y666746D01*
G02X266380Y667163I500J0D01*
G03X266761Y669303I-830J1252D01*
G02X266906Y670645I806J592D01*
G03X267103Y672688I-993J1127D01*
G01X266988Y672838D01*
X267012Y673213D01*
X267830Y674031D01*
X294654D01*
X300615Y668070D01*
X313601D01*
X321366Y675835D01*
X325213D01*
X325460Y675676D01*
X325521Y675541D01*
G03X328259I1369J618D01*
G02X328715Y675835I456J-206D01*
G01X350500D01*
X358501Y667834D01*
X360312D01*
G02X360673Y667679I-1J-500D01*
G03X362847I1087J1037D01*
G02X363208Y667834I362J-345D01*
G01X363800D01*
X366033Y670067D01*
Y671465D01*
G02X366190Y671829I500J0D01*
G03Y674015I-1030J1093D01*
G02X366033Y674379I343J364D01*
G01Y675535D01*
G02X366173Y675882I500J0D01*
G03Y677964I-1083J1041D01*
G02X366033Y678311I360J347D01*
G01Y682553D01*
X366547Y683067D01*
G02X367025Y683197I353J-354D01*
G03X368258Y683420I374J1455D01*
G01X368387Y683510D01*
X398544D01*
G02X398974Y683264I-1J-500D01*
G03X401560I1293J765D01*
G02X401990Y683510I431J-254D01*
G01X429761D01*
X429901Y683391D01*
G03X431845I972J1145D01*
G01X431985Y683510D01*
X439285D01*
G02X439635Y683367I0J-500D01*
G03X441741I1053J1071D01*
G02X442091Y683510I350J-357D01*
G01X460513D01*
G02X460875Y683356I1J-500D01*
G03X463045I1085J1038D01*
G02X463407Y683510I361J-346D01*
G01X476754D01*
X477774Y684530D01*
X479736D01*
G02X480108Y684364I0J-500D01*
G03X482346I1119J1002D01*
G02X482718Y684530I372J-334D01*
G01X492184D01*
X493694Y686040D01*
G02X494116Y686181I353J-354D01*
G03X495811Y687876I207J1488D01*
G01X495794Y687993D01*
X495869Y688215D01*
X503776Y696122D01*
Y720322D01*
X506074Y722620D01*
X506252Y722637D01*
G03X507035Y722953I-148J1495D01*
G01X507171Y723060D01*
X508763D01*
X508902Y722946D01*
G03X510808I953J1161D01*
G01X510947Y723060D01*
X513822D01*
X513960Y722950D01*
G03X515842I941J1170D01*
G01X515980Y723060D01*
X516736D01*
X517004Y722853D01*
X517048Y722688D01*
G03X519952I1452J385D01*
G02X520435Y723060I483J-128D01*
G01X522303D01*
X522439Y722952D01*
G03X524301I931J1179D01*
G01X524437Y723060D01*
X530741D01*
X530881Y722943D01*
G03X532809I964J1152D01*
G01X532949Y723060D01*
X543532D01*
X543609Y723035D01*
G03X544555I473J1425D01*
G01X544632Y723060D01*
X545486D01*
X545624Y722949D01*
G03X547508I942J1170D01*
G01X547646Y723060D01*
X548387D01*
X548479Y723023D01*
G03X548721Y722946I575J1388D01*
G02X549092Y722320I-109J-488D01*
G03X550508Y720401I1443J-417D01*
G02X551490Y719401I-18J-1000D01*
G01Y672046D01*
X553346Y670190D01*
X580736D01*
X590418Y660508D01*
X590481Y660223D01*
X590430Y660086D01*
G03X592358Y658158I1410J-518D01*
G02X592884Y658042I172J-469D01*
G01X594969Y655957D01*
X595039Y655707D01*
X595009Y655580D01*
G03X596819Y653770I1461J-349D01*
G01X596946Y653800D01*
X597196Y653730D01*
X614989Y635937D01*
X615024Y635811D01*
G03X616067Y634768I1447J404D01*
G01X616193Y634733D01*
X622452Y628474D01*
X622486Y628342D01*
G03X623562Y627266I1454J378D01*
G01X623694Y627232D01*
X667770Y583156D01*
Y533556D01*
X667658Y533418D01*
G03Y531522I1165J-948D01*
G01X667770Y531384D01*
Y529190D01*
G02X667609Y528822I-500J0D01*
G03Y526614I1018J-1104D01*
G02X667770Y526246I-339J-368D01*
G01Y515565D01*
X667679Y515367D01*
X667595Y515295D01*
G03Y513015I978J-1140D01*
G02X667770Y512635I-325J-380D01*
G01Y479758D01*
X667562Y479489D01*
X667396Y479446D01*
G03Y476538I378J-1454D01*
G02X667770Y476054I-126J-484D01*
G01Y418263D01*
X667647Y418122D01*
G03Y416148I1132J-987D01*
G01X667770Y416007D01*
Y377902D01*
X667756Y377844D01*
G03Y377132I1459J-356D01*
G01X667770Y377074D01*
Y365859D01*
X667683Y365732D01*
G03Y364042I1242J-845D01*
G01X667770Y363915D01*
Y293754D01*
X596493Y222477D01*
X596234Y222408D01*
X596103Y222444D01*
G03X594258Y220599I-396J-1449D01*
G01X594294Y220468D01*
X594225Y220209D01*
X590436Y216420D01*
X551816D01*
X549072Y213676D01*
G02X548520Y213570I-354J353D01*
G03X546547Y211597I-593J-1380D01*
G01X546608Y211455D01*
X546550Y211154D01*
X543595Y208199D01*
X543572Y208181D01*
G03X543319Y207928I928J-1181D01*
G01X543301Y207905D01*
X533405Y198009D01*
X533244Y197984D01*
G03X531990Y196730I230J-1484D01*
G01X531965Y196569D01*
X530041Y194645D01*
G02X529664Y194499I-354J354D01*
G03X528092Y192927I-72J-1500D01*
G01X528097Y192821D01*
X528021Y192625D01*
X523570Y188174D01*
Y99947D01*
X523541Y99865D01*
G03Y98853I1414J-506D01*
G01X523570Y98771D01*
Y82956D01*
X532756Y73770D01*
X580814D01*
X585270Y78226D01*
Y106160D01*
G02X585770Y106660I500J0D01*
G01X609423D01*
X609564Y106539D01*
G03X611522I979J1139D01*
G01X611663Y106660D01*
X644916D01*
X654026Y97550D01*
X676234D01*
G02X676993Y95899I0J-1000D01*
G03X700960I11984J-10269D01*
G02X701719Y97550I759J651D01*
G01X704436D01*
X707476Y94510D01*
X753674D01*
X755440Y96276D01*
Y122551D01*
G02X755600Y122918I500J0D01*
G03X755202Y125387I-1020J1102D01*
G01X755119Y125425D01*
X748954Y131590D01*
X738919D01*
X738829Y131626D01*
G03X737711I-559J-1394D01*
G01X737621Y131590D01*
X727183D01*
X727077Y131644D01*
G03X725723I-677J-1341D01*
G01X725617Y131590D01*
X722134D01*
X701810Y151914D01*
Y210229D01*
G02X702154Y210705I500J1D01*
G03Y213559I-467J1427D01*
G01X702000Y213610D01*
X701810Y213872D01*
Y215402D01*
G02X701970Y215768I500J-1D01*
G03Y217968I-1023J1100D01*
G02X701810Y218334I340J367D01*
G01Y219859D01*
G02X701981Y220236I500J0D01*
G03Y222500I-987J1132D01*
G02X701810Y222877I329J377D01*
G01Y273866D01*
X716310Y288366D01*
Y457906D01*
X716404Y458107D01*
X716490Y458178D01*
G03Y460486I-962J1154D01*
G02X716310Y460870I320J384D01*
G01Y479776D01*
G02X716440Y480112I500J0D01*
G03Y482132I-1112J1010D01*
G02X716310Y482468I370J336D01*
G01Y515256D01*
X716475Y515505D01*
X716613Y515565D01*
G03Y518325I-592J1380D01*
G01X716475Y518385D01*
X716310Y518634D01*
Y523538D01*
X716511Y523805D01*
X716673Y523851D01*
G03Y526739I-413J1444D01*
G01X716511Y526785D01*
X716310Y527052D01*
Y619172D01*
X716428Y619312D01*
G03Y621252I-1146J970D01*
G01X716310Y621392D01*
Y622954D01*
X672892Y666372D01*
X672859Y666508D01*
G03X671757Y667610I-1459J-357D01*
G01X671621Y667643D01*
X639580Y699684D01*
Y733388D01*
X639687Y733600D01*
X639783Y733671D01*
G03Y736087I-893J1208D01*
G01X639687Y736158D01*
X639580Y736370D01*
Y761187D01*
X639678Y761319D01*
G03Y763105I-1208J893D01*
G01X639580Y763237D01*
Y817152D01*
G02X640080Y817652I500J0D01*
G01X682744D01*
G02X683244Y817152I0J-500D01*
G01Y793925D01*
G37*
G36*
G01X714017Y456239D02*
G03Y453505I622J-1367D01*
G02X714310Y453050I-207J-455D01*
G01Y289194D01*
X699810Y274694D01*
Y222304D01*
X699731Y222180D01*
G03Y220556I1263J-812D01*
G01X699810Y220432D01*
Y217862D01*
X699719Y217733D01*
G03Y216003I1228J-865D01*
G01X699810Y215874D01*
Y151086D01*
X704361Y146535D01*
G02X704501Y146098I-353J-354D01*
G01X704486Y146012D01*
X704473Y145973D01*
G03X713993Y136453I7102J-2418D01*
G01X714032Y136466D01*
X714118Y136481D01*
G02X714555Y136341I83J-493D01*
G01X721306Y129590D01*
X724925D01*
X725134Y129487D01*
X725205Y129393D01*
G03X727595I1195J910D01*
G01X727666Y129487D01*
X727875Y129590D01*
X736626D01*
X737029Y129379D01*
X737095Y129296D01*
G03X739504Y129375I1175J936D01*
G01X739575Y129477D01*
X739791Y129590D01*
X745214D01*
G02X745680Y129271I0J-500D01*
G03X747957Y128595I1400J544D01*
G02X749235Y128481I571J-821D01*
G01X753055Y124661D01*
X753128Y124424D01*
X753105Y124302D01*
G03X753350Y123159I1475J-282D01*
G01X753440Y123029D01*
Y97104D01*
X752846Y96510D01*
X708304D01*
X705264Y99550D01*
X698960D01*
G02X698460Y100050I0J500D01*
G01Y105315D01*
G03X698458Y105483I-9483J-29D01*
G03X698457Y105527I-9481J-193D01*
G01Y106143D01*
X698422Y106178D01*
X698403Y106353D01*
G03X679550Y106352I-9426J-1037D01*
G01X679531Y106177D01*
X679497Y106143D01*
Y105566D01*
G03X679494Y105315I9480J-239D01*
G01Y100028D01*
G02X678994Y99550I-500J23D01*
G01X654854D01*
X645744Y108660D01*
X611889D01*
X611559Y108788D01*
X611496Y108839D01*
G03X609590I-953J-1161D01*
G01X609527Y108788D01*
X609197Y108660D01*
X583270D01*
Y79054D01*
X579986Y75770D01*
X533584D01*
X525570Y83784D01*
Y97822D01*
X525687Y98041D01*
X525792Y98112D01*
G03Y100606I-837J1247D01*
G01X525687Y100677D01*
X525570Y100896D01*
Y187346D01*
X529718Y191494D01*
X529870Y191523D01*
G03X531068Y192721I-278J1476D01*
G01X531097Y192873D01*
X533076Y194852D01*
G02X533441Y194998I353J-354D01*
G03X534976Y196533I33J1502D01*
G02X535122Y196898I500J12D01*
G01X543641Y205417D01*
G02X544120Y205547I353J-354D01*
G03X545953Y207380I380J1453D01*
G01X545919Y207509D01*
X545989Y207765D01*
X552644Y214420D01*
X591264D01*
X669770Y292926D01*
Y363404D01*
X669931Y363768D01*
X669995Y363833D01*
G03Y365941I-1070J1054D01*
G01X669931Y366006D01*
X669770Y366370D01*
Y375787D01*
X670003Y376204D01*
X670093Y376269D01*
G03Y378707I-878J1219D01*
G01X670003Y378772D01*
X669770Y379189D01*
Y384418D01*
G02X670088Y384884I500J0D01*
G03Y387682I-548J1399D01*
G01X669943Y387739D01*
X669770Y387992D01*
Y393361D01*
G02X670063Y393816I500J0D01*
G03X670168Y396497I-623J1367D01*
G01X670058Y396558D01*
X669770Y397005D01*
Y400918D01*
G02X670088Y401384I500J0D01*
G03X670201Y404132I-548J1399D01*
G01X670082Y404190D01*
X669770Y404647D01*
Y406661D01*
G02X670063Y407116I500J0D01*
G03Y409850I-623J1367D01*
G01X669928Y409911D01*
X669770Y410157D01*
Y415799D01*
X669896Y416128D01*
X669946Y416189D01*
G03Y418081I-1167J946D01*
G01X669896Y418142D01*
X669770Y418471D01*
Y466105D01*
X670128Y466577D01*
X670262Y466628D01*
G03X670135Y469478I-534J1404D01*
G01X670134D01*
G02X669770Y469959I136J481D01*
G01Y513236D01*
X669846Y513358D01*
G03Y514952I-1273J797D01*
G01X669770Y515074D01*
Y526731D01*
X669860Y526860D01*
G03Y528576I-1233J858D01*
G01X669770Y528705D01*
Y531086D01*
X669907Y531426D01*
X669961Y531489D01*
G03Y533451I-1138J981D01*
G01X669907Y533514D01*
X669770Y533854D01*
Y583984D01*
X625499Y628255D01*
X625424Y628464D01*
X625435Y628576D01*
G03X623796Y630215I-1495J144D01*
G02X623395Y630359I-48J498D01*
G01X618027Y635727D01*
X617952Y635940D01*
X617964Y636053D01*
G03X616309Y637708I-1493J162D01*
G02X615902Y637852I-53J497D01*
G01X597772Y655982D01*
X597742Y656030D01*
G03X597269Y656503I-1272J-799D01*
G01X597221Y656533D01*
X581564Y672190D01*
X554174D01*
X553490Y672874D01*
Y721514D01*
X550560Y724444D01*
X550538Y724611D01*
G03X548561Y725833I-1489J-199D01*
G03X547980Y725467I489J-1420D01*
G02X547360Y725394I-356J351D01*
G03X545793Y725407I-794J-1275D01*
G02X545173Y725492I-257J429D01*
G03X542827Y725285I-1091J-1032D01*
G02X542409Y725060I-418J275D01*
G01X533209D01*
X532875Y725192D01*
X532812Y725244D01*
G03X530878I-967J-1149D01*
G01X530815Y725192D01*
X530481Y725060D01*
X524772D01*
G02X524422Y725203I0J500D01*
G03X522318I-1052J-1072D01*
G02X521968Y725060I-350J357D01*
G01X516292D01*
G02X515944Y725200I-1J500D01*
G03X513858I-1043J-1080D01*
G02X513510Y725060I-347J360D01*
G01X511232D01*
G02X510888Y725197I0J500D01*
G03X508822I-1033J-1090D01*
G02X508478Y725060I-344J363D01*
G01X507508D01*
G02X507158Y725203I0J500D01*
G03X504604Y724172I-1053J-1071D01*
G01X504598Y723972D01*
X501776Y721150D01*
Y696950D01*
X493956Y689130D01*
X493845Y689093D01*
G03X492899Y688147I478J-1424D01*
G01X492862Y688036D01*
X491356Y686530D01*
X482188D01*
X482062Y686614D01*
G03X480392I-835J-1248D01*
G01X480266Y686530D01*
X476946D01*
X475926Y685510D01*
X462978D01*
X462847Y685606D01*
G03X461073I-887J-1212D01*
G01X460942Y685510D01*
X441754D01*
X441618Y685617D01*
G03X439758I-930J-1179D01*
G01X439622Y685510D01*
X432228D01*
G02X431889Y685642I0J500D01*
G03X429857I-1016J-1106D01*
G02X429518Y685510I-339J368D01*
G01X400520D01*
X400484Y685515D01*
G03X400050I-217J-1486D01*
G01X400014Y685510D01*
X368870D01*
X368509Y685668D01*
X368445Y685731D01*
G03X366884Y686063I-1045J-1079D01*
G03X366196Y685551I515J-1411D01*
G01X366174Y685522D01*
X364033Y683381D01*
Y682124D01*
X363868Y681874D01*
X363730Y681815D01*
G03Y679053I590J-1381D01*
G01X363868Y678994D01*
X364033Y678744D01*
Y678005D01*
X363922Y677867D01*
G03Y675979I1168J-944D01*
G01X364033Y675841D01*
Y673928D01*
X363939Y673797D01*
G03Y672047I1221J-875D01*
G01X364033Y671916D01*
Y670895D01*
X363189Y670051D01*
G02X362567Y669983I-353J354D01*
G03X360875Y669930I-807J-1267D01*
G01X360743Y669834D01*
X359329D01*
X351328Y677835D01*
X320538D01*
X312773Y670070D01*
X301443D01*
X295482Y676031D01*
X281513D01*
X281267Y676188D01*
X281205Y676321D01*
G03X278481Y676320I-1362J-633D01*
G02X278027Y676031I-453J211D01*
G01X267002D01*
X264156Y673185D01*
Y668981D01*
X264129Y668902D01*
G03Y667928I1421J-487D01*
G01X264156Y667849D01*
Y635609D01*
X262487Y633940D01*
X240018D01*
X235979Y637979D01*
X235943Y638103D01*
G03X234918Y639128I-1443J-418D01*
G01X234794Y639164D01*
X231335Y642623D01*
Y671240D01*
X231350Y671301D01*
G03Y672043I-1455J371D01*
G01X231335Y672104D01*
Y704673D01*
X237536Y710874D01*
G02X238004Y711007I353J-354D01*
G03X239810Y712813I344J1462D01*
G01X239780Y712940D01*
X239851Y713189D01*
X254297Y727635D01*
X353447D01*
X353584Y727526D01*
G03X355456I936J1175D01*
G01X355593Y727635D01*
X363027D01*
X363285Y727455D01*
X363339Y727306D01*
G03X366113Y727190I1411J515D01*
G01X366170Y727312D01*
X366631Y727635D01*
X383109D01*
G03X410929Y741142I10631J13507D01*
G01Y817152D01*
G02X411429Y817652I500J0D01*
G01X637080D01*
G02X637580Y817152I0J-500D01*
G01Y767697D01*
G02X637420Y767330I-500J0D01*
G03Y765126I1020J-1102D01*
G02X637580Y764759I-340J-367D01*
G01Y763653D01*
X637430Y763299D01*
X637370Y763235D01*
G03Y761189I1100J-1023D01*
G01X637430Y761125D01*
X637580Y760771D01*
Y735623D01*
X637532Y735521D01*
G03Y734237I1358J-642D01*
G01X637580Y734135D01*
Y698856D01*
X669837Y666599D01*
X669913Y666391D01*
X669906Y666310D01*
G03X671559Y664657I1494J-159D01*
G01X671640Y664664D01*
X671848Y664588D01*
X714310Y622126D01*
Y621639D01*
G02X714178Y621300I-500J0D01*
G03Y619264I1104J-1018D01*
G02X714310Y618925I-368J-339D01*
G01Y482242D01*
X714189Y482101D01*
G03Y480143I1139J-979D01*
G01X714310Y480002D01*
Y460222D01*
X714239Y460103D01*
G03Y458561I1289J-771D01*
G01X714310Y458442D01*
Y456694D01*
G02X714017Y456239I-500J0D01*
G37*
%LPD*%
G75*
G36*
G01X87339Y714138D02*
Y721342D01*
X87486Y721489D01*
X87513Y721643D01*
G02X109339I10913J-1958D01*
G01X109366Y721489D01*
X109513Y721342D01*
Y714138D01*
G03X109696Y713751I500J0D01*
G02X87156I-11270J-13751D01*
G03X87339Y714138I-317J387D01*
G37*
G36*
G01X612516Y69078D02*
G02X608614Y65176I-3902J0D01*
G02X604612Y69178I0J4002D01*
G02X612516I3952J0D01*
G01Y69078D01*
G37*
G36*
G01X587858D02*
G02X583956Y65176I-3902J0D01*
G02X579954Y69178I0J4002D01*
G02X587858I3952J0D01*
G01Y69078D01*
G37*
G36*
G01X397421Y38554D02*
G02X396249Y35852I-3703J1D01*
G01X395926D01*
G03X395426Y35352I0J-501D01*
G01Y35269D01*
G02X392030Y35258I-1709J3285D01*
G01Y35354D01*
G03X391530Y35854I-500J0D01*
G01X391184D01*
G02X391187Y41256I2534J2700D01*
G01X391532D01*
G03X392032Y41756I0J500D01*
G01Y41851D01*
G02X395426Y41839I1685J-3297D01*
G01Y41756D01*
G03X395926Y41256I500J1D01*
G01X396249D01*
G02X397421Y38554I-2531J-2703D01*
G37*
G36*
G01X358051D02*
G02X356879Y35852I-3703J1D01*
G01X356556D01*
G03X356056Y35352I1J-501D01*
G01Y35269D01*
G02X352660Y35258I-1709J3285D01*
G01Y35354D01*
G03X352160Y35854I-500J0D01*
G01X351814D01*
G02X351817Y41256I2534J2700D01*
G01X352162D01*
G03X352662Y41756I0J500D01*
G01Y41851D01*
G02X356056Y41839I1685J-3297D01*
G01Y41756D01*
G03X356556Y41256I501J1D01*
G01X356879D01*
G02X358051Y38554I-2531J-2703D01*
G37*
G36*
G01X696068Y685704D02*
X695997Y685668D01*
X694940Y684612D01*
X694749Y684803D01*
G03X694230Y684920I-353J-354D01*
G02X678806Y711871I-5254J14882D01*
G03X679494Y713350I-1246J1479D01*
G01Y719488D01*
G02X679497Y719700I9483J-28D01*
G01Y720316D01*
X679532Y720351D01*
X679551Y720526D01*
G02X698403I9426J-1038D01*
G01X698422Y720351D01*
X698457Y720316D01*
Y719700D01*
G02X698460Y719488I-9480J-240D01*
G01Y713350D01*
G03X699148Y711871I1934J0D01*
G02X696068Y685704I-10171J-12068D01*
G37*
G36*
G01X482400Y574692D02*
G02Y572434I-990J-1129D01*
G03X482230Y572058I330J-376D01*
G01Y554688D01*
G03X482393Y554319I500J0D01*
G02Y552101I-1013J-1109D01*
G03X482230Y551732I337J-369D01*
G01Y502806D01*
X477684Y498260D01*
X459566D01*
X455950Y501876D01*
Y527990D01*
G03X455768Y528376I-500J0D01*
G02Y530696I954J1160D01*
G03X455950Y531082I-318J386D01*
G01Y572646D01*
X449646Y578950D01*
X383150D01*
G03X382650Y578450I0J-500D01*
G01Y556090D01*
G03X383011Y555609I500J-1D01*
G02Y552723I-416J-1443D01*
G03X382650Y552242I139J-480D01*
G01Y542094D01*
X382811Y541846D01*
X382946Y541785D01*
G02X383599Y539606I-613J-1371D01*
G03X383704Y538393I843J-538D01*
G02X383012Y535936I-1108J-1014D01*
G03X382650Y535455I138J-481D01*
G01Y534585D01*
X382856Y534317D01*
X383021Y534273D01*
G02X383805Y531884I-389J-1451D01*
G03Y531260I391J-312D01*
G02Y529384I-1173J-938D01*
G03Y528760I391J-312D01*
G02X383021Y526371I-1173J-938D01*
G01X382856Y526327D01*
X382650Y526059D01*
Y510366D01*
X376284Y504000D01*
X355041D01*
X354814Y503872D01*
X354745Y503759D01*
G02X352175I-1285J777D01*
G01X352106Y503872D01*
X351879Y504000D01*
X348094D01*
X317435Y473341D01*
G03X317337Y472773I353J-353D01*
G02X316895Y470937I-1357J-645D01*
G03X316700Y470541I305J-396D01*
G01Y439546D01*
X316797Y439343D01*
X316885Y439271D01*
G02Y436937I-945J-1167D01*
G01X316797Y436865D01*
X316700Y436662D01*
Y420126D01*
X308304Y411730D01*
X266456D01*
X263220Y414966D01*
Y435174D01*
X266706Y438660D01*
X275896D01*
X277450Y440214D01*
Y479434D01*
X277244Y479702D01*
X277080Y479747D01*
G02Y482647I390J1450D01*
G01X277244Y482692D01*
X277450Y482960D01*
Y487044D01*
X286853Y496447D01*
X286876Y496478D01*
G02X287184Y496786I1133J-825D01*
G01X287215Y496809D01*
X291876Y501470D01*
X309256D01*
X338624Y530838D01*
G03X338748Y531340I-353J354D01*
G02X340629Y533221I1434J447D01*
G03X341131Y533345I148J477D01*
G01X347170Y539384D01*
Y574066D01*
X346800Y574436D01*
Y624234D01*
X349146Y626580D01*
X376860D01*
G03X377360Y627080I0J500D01*
G01Y642014D01*
X379966Y644620D01*
X393509D01*
X393625Y644688D01*
G02X395135I755J-1299D01*
G01X395251Y644620D01*
X435601D01*
G03X435975Y644789I-1J500D01*
G02X438225I1125J-996D01*
G03X438599Y644620I375J331D01*
G01X475744D01*
X482230Y638134D01*
Y594737D01*
G03X482383Y594377I500J0D01*
G02Y592215I-1043J-1081D01*
G03X482230Y591855I347J-360D01*
G01Y575068D01*
G03X482400Y574692I500J0D01*
G37*
G36*
G01X107714Y99535D02*
G03X108424Y98039I1934J2D01*
G02X88315Y73709I-9996J-12214D01*
G02X85848Y95361I10110J12119D01*
G01X85950Y95495D01*
Y95540D01*
X86128Y95719D01*
X86144Y95739D01*
G02X88506Y98103I12283J-9911D01*
G03X89142Y99535I-1298J1434D01*
G01Y105510D01*
G02X107714I9286J0D01*
G01Y99535D01*
G37*
G36*
G01X400781Y274272D02*
G02X398435I-1173J939D01*
G03X398045Y274460I-391J-312D01*
G01X393521D01*
X393389Y274365D01*
G02X391627I-881J1216D01*
G01X391495Y274460D01*
X319494D01*
X319230Y274196D01*
Y103854D01*
X332390Y90694D01*
Y66766D01*
X328264Y62640D01*
X328072D01*
G03X327642Y62396I-1J-500D01*
G02X325064I-1289J771D01*
G03X324634Y62640I-429J-256D01*
G01X324432D01*
G03X324002Y62396I-1J-500D01*
G02X321424I-1289J771D01*
G03X320994Y62640I-429J-256D01*
G01X320262D01*
G03X319832Y62396I-1J-500D01*
G02X317254I-1289J771D01*
G03X316824Y62640I-429J-256D01*
G01X316359D01*
G03X315929Y62396I-1J-500D01*
G02X313351I-1289J771D01*
G03X312921Y62640I-429J-256D01*
G01X312202D01*
G03X311772Y62396I-1J-500D01*
G02X309194I-1289J771D01*
G03X308764Y62640I-429J-256D01*
G01X308412D01*
G03X307982Y62396I-1J-500D01*
G02X305404I-1289J771D01*
G03X304974Y62640I-429J-256D01*
G01X304772D01*
G03X304342Y62396I-1J-500D01*
G02X301764I-1289J771D01*
G03X301334Y62640I-429J-256D01*
G01X300602D01*
G03X300172Y62396I-1J-500D01*
G02X297594I-1289J771D01*
G03X297164Y62640I-429J-256D01*
G01X296622D01*
G03X296192Y62396I-1J-500D01*
G02X293614I-1289J771D01*
G03X293184Y62640I-429J-256D01*
G01X292542D01*
G03X292112Y62396I-1J-500D01*
G02X289534I-1289J771D01*
G03X289104Y62640I-429J-256D01*
G01X283742D01*
G03X283312Y62396I-1J-500D01*
G02X280734I-1289J771D01*
G03X280304Y62640I-429J-256D01*
G01X279572D01*
G03X279142Y62396I-1J-500D01*
G02X276564I-1289J771D01*
G03X276134Y62640I-429J-256D01*
G01X275592D01*
G03X275162Y62396I-1J-500D01*
G02X272584I-1289J771D01*
G03X272154Y62640I-429J-256D01*
G01X271512D01*
G03X271082Y62396I-1J-500D01*
G02X268504I-1289J771D01*
G03X268074Y62640I-429J-256D01*
G01X255353D01*
X255133Y62522D01*
X255063Y62416D01*
G02X252557I-1253J828D01*
G03X252140Y62640I-417J-276D01*
G01X196396D01*
X191340Y67696D01*
Y86955D01*
X191219Y87178D01*
X191112Y87247D01*
G02Y89767I818J1260D01*
G01X191219Y89836D01*
X191340Y90059D01*
Y268425D01*
G03X191095Y268856I-500J1D01*
G02Y271440I765J1292D01*
G03X191340Y271871I-255J430D01*
G01Y272440D01*
G03X190840Y272940I-500J0D01*
G01X175790D01*
X175697Y272901D01*
G02X174539I-579J1386D01*
G01X174446Y272940D01*
X111656D01*
X99600Y284996D01*
Y341863D01*
G03X99294Y342323I-500J-1D01*
G02X97252Y355634I3068J7283D01*
G03X97312Y357104I-647J763D01*
G01X59960Y394456D01*
Y461214D01*
X61896Y463150D01*
X134234D01*
X148273Y449111D01*
X148329Y449078D01*
G02X148875Y448532I-753J-1299D01*
G01X148908Y448476D01*
X192938Y404446D01*
X193067Y404411D01*
G02X194126Y403352I-391J-1450D01*
G01X194161Y403223D01*
X199540Y397844D01*
X199826Y397781D01*
X199964Y397833D01*
G02X201896Y395901I524J-1408D01*
G01X201844Y395763D01*
X201907Y395477D01*
X220150Y377234D01*
Y320064D01*
X221084Y319130D01*
X239321D01*
G03X239805Y319503I0J500D01*
G02X242711I1453J-380D01*
G01X242754Y319338D01*
X243024Y319130D01*
X252883D01*
X254955Y321202D01*
G03X255019Y321829I-354J353D01*
G02X255386Y323862I1257J823D01*
G03X255590Y324265I-296J403D01*
G01Y353524D01*
X258126Y356060D01*
X267859D01*
G03X268258Y356259I0J500D01*
G02X270654I1198J-906D01*
G03X271053Y356060I399J301D01*
G01X339406D01*
X359400Y376054D01*
Y394493D01*
G03X359262Y394837I-500J-1D01*
G02Y396909I1088J1036D01*
G03X359400Y397253I-362J345D01*
G01Y432044D01*
X389326Y461970D01*
X475244D01*
X482910Y454304D01*
Y338796D01*
X423240Y279126D01*
X423218Y278955D01*
G02X421914Y277651I-1490J186D01*
G01X421743Y277629D01*
X418574Y274460D01*
X401171D01*
G03X400781Y274272I1J-500D01*
G37*
G54D47*
X-44872Y125213D03*
Y141213D03*
Y232533D03*
Y248533D03*
Y738493D03*
Y754493D03*
X-26872Y125213D03*
Y141213D03*
Y232533D03*
Y248533D03*
Y738493D03*
Y754493D03*
G54D51*
X43898Y168544D03*
Y231457D03*
G54D50*
X151969Y98622D03*
G54D49*
X414961D03*
G54D48*
X434102Y232640D03*
G54D52*
X25455Y303232D03*
Y356832D03*
G54D53*
X102362Y247244D03*
X354331D03*
%LPC*%
G75*
G36*
G01X169191Y424853D02*
G03X171232Y422812I1315J-726D01*
G02X171828Y422728I242J-437D01*
G01X191038Y403518D01*
G02X191182Y403114I-354J-354D01*
G03X192829Y401467I1494J-153D01*
G01X192942Y401478D01*
X193153Y401403D01*
X218150Y376406D01*
Y319236D01*
X220256Y317130D01*
X244313D01*
G02X244813Y316630I0J-500D01*
G01Y302853D01*
X253872Y293794D01*
X258229D01*
X260480Y291543D01*
Y276964D01*
X258456Y274940D01*
X242629D01*
X242373Y275118D01*
X242318Y275266D01*
G03X239502I-1408J-524D01*
G01X239447Y275118D01*
X239191Y274940D01*
X233134D01*
X232923Y275046D01*
X232852Y275141D01*
G03X230570Y275289I-1204J-898D01*
G02X229864Y275278I-359J348D01*
G03X227644Y275130I-1043J-1081D01*
G02X227252Y274940I-392J310D01*
G01X217520D01*
X217322Y275031D01*
X217251Y275115D01*
G03X215237Y275362I-1142J-976D01*
G02X214049Y275381I-581J814D01*
G03X211967Y275127I-911J-1194D01*
G02X211577Y274940I-390J313D01*
G01X203314D01*
X203073Y275088D01*
X203009Y275216D01*
G03X200325I-1342J-674D01*
G01X200261Y275088D01*
X200020Y274940D01*
X183567D01*
G02X183122Y275211I0J500D01*
G03X180926Y275705I-1304J-671D01*
G02X179710I-608J794D01*
G03X177514Y275211I-892J-1165D01*
G02X177069Y274940I-445J229D01*
G01X176632D01*
X176416Y275052D01*
X176346Y275152D01*
G03X173890I-1228J-865D01*
G02X173481Y274940I-409J288D01*
G01X112484D01*
X101600Y285824D01*
Y340707D01*
G02X102573Y341706I1000J-1D01*
G03X100348Y357247I-211J7900D01*
G02X99867Y357377I-127J484D01*
G01X61960Y395284D01*
Y460386D01*
X62724Y461150D01*
X133406D01*
X146069Y448487D01*
X146140Y448239D01*
X146112Y448113D01*
G03X147910Y446315I1464J-334D01*
G01X148036Y446343D01*
X148284Y446272D01*
X169107Y425449D01*
G02X169191Y424853I-353J-354D01*
G37*
G36*
G01X197224Y64640D02*
X193340Y68524D01*
Y87984D01*
X193363Y88057D01*
G03Y88957I-1433J450D01*
G01X193340Y89030D01*
Y269889D01*
X193345Y269926D01*
G03Y270370I-1485J222D01*
G01X193340Y270407D01*
Y271846D01*
X194434Y272940D01*
X212291D01*
X212404Y272876D01*
G03X213872I734J1311D01*
G01X213985Y272940D01*
X215193D01*
X215315Y272864D01*
G03X216903I794J1275D01*
G01X217025Y272940D01*
X222667D01*
X222917Y272775D01*
X222976Y272637D01*
G03X225738I1381J591D01*
G01X225797Y272775D01*
X226047Y272940D01*
X227989D01*
X228101Y272879D01*
G03X229541I720J1318D01*
G01X229653Y272940D01*
X230892D01*
X230995Y272890D01*
G03X232301I653J1353D01*
G01X232404Y272940D01*
X259284D01*
X261046Y274702D01*
G02X261754I354J-353D01*
G01X261996Y274460D01*
X293958D01*
G02X294295Y274329I0J-500D01*
G03X296319I1012J1110D01*
G02X296656Y274460I337J-369D01*
G01X316730D01*
G02X317230Y273960I0J-500D01*
G01Y103026D01*
X330390Y89866D01*
Y67594D01*
X327436Y64640D01*
X326650D01*
X326608Y64647D01*
G03X326098I-255J-1480D01*
G01X326056Y64640D01*
X323010D01*
X322968Y64647D01*
G03X322458I-255J-1480D01*
G01X322416Y64640D01*
X318840D01*
X318798Y64647D01*
G03X318288I-255J-1480D01*
G01X318246Y64640D01*
X314937D01*
X314895Y64647D01*
G03X314385I-255J-1480D01*
G01X314343Y64640D01*
X310780D01*
X310738Y64647D01*
G03X310228I-255J-1480D01*
G01X310186Y64640D01*
X306990D01*
X306948Y64647D01*
G03X306438I-255J-1480D01*
G01X306396Y64640D01*
X303350D01*
X303308Y64647D01*
G03X302798I-255J-1480D01*
G01X302756Y64640D01*
X299180D01*
X299138Y64647D01*
G03X298628I-255J-1480D01*
G01X298586Y64640D01*
X295200D01*
X295158Y64647D01*
G03X294648I-255J-1480D01*
G01X294606Y64640D01*
X291120D01*
X291078Y64647D01*
G03X290568I-255J-1480D01*
G01X290526Y64640D01*
X282320D01*
X282278Y64647D01*
G03X281768I-255J-1480D01*
G01X281726Y64640D01*
X278150D01*
X278108Y64647D01*
G03X277598I-255J-1480D01*
G01X277556Y64640D01*
X274170D01*
X274128Y64647D01*
G03X273618I-255J-1480D01*
G01X273576Y64640D01*
X270090D01*
X270048Y64647D01*
G03X269538I-255J-1480D01*
G01X269496Y64640D01*
X254370D01*
X254292Y64666D01*
G03X253328I-482J-1422D01*
G01X253250Y64640D01*
X197224D01*
G37*
G36*
G01X361400Y387312D02*
G02X361665Y387754I500J1D01*
G03Y390406I-705J1326D01*
G01X361542Y390472D01*
X361400Y390708D01*
Y394784D01*
X361513Y394922D01*
G03Y396824I-1163J951D01*
G01X361400Y396962D01*
Y431216D01*
X390154Y459970D01*
X474416D01*
X480910Y453476D01*
Y423943D01*
G02X480632Y423495I-500J0D01*
G03Y420805I668J-1345D01*
G01X480760Y420741D01*
X480910Y420500D01*
Y339624D01*
X421930Y280644D01*
X421723Y280643D01*
G03X420226Y279146I5J-1502D01*
G01X420225Y278939D01*
X417746Y276460D01*
X400452D01*
X400339Y276523D01*
G03X398877I-731J-1312D01*
G01X398764Y276460D01*
X393959D01*
G02X393597Y276616I1J500D01*
G03X391419I-1089J-1035D01*
G02X391057Y276460I-363J344D01*
G01X296424D01*
X296284Y276580D01*
G03X294330I-977J-1141D01*
G01X294190Y276460D01*
X287648D01*
X287409Y276606D01*
X287345Y276731D01*
G03X284675I-1335J-689D01*
G02X284231Y276460I-444J229D01*
G01X262824D01*
X262480Y276804D01*
Y292371D01*
X259057Y295794D01*
X254700D01*
X248655Y301839D01*
G02X248569Y302431I353J354D01*
G03X247297Y304649I-1320J717D01*
G02X246813Y305149I16J500D01*
G01Y316630D01*
G02X247313Y317130I500J0D01*
G01X253711D01*
X257590Y321009D01*
Y321916D01*
X257637Y322017D01*
G03Y323287I-1361J635D01*
G01X257590Y323388D01*
Y352696D01*
X258047Y353153D01*
X258414Y353182D01*
X258563Y353074D01*
G03X260842Y353743I880J1217D01*
G02X261308Y354060I465J-183D01*
G01X268683D01*
X268788Y354008D01*
G03X270124I668J1345D01*
G01X270229Y354060D01*
X317986D01*
X318234Y353899D01*
X318294Y353764D01*
G03X320715Y353301I1372J612D01*
G02X322063Y353344I698J-716D01*
G03X324372Y353791I977J1141D01*
G02X324815Y354060I443J-231D01*
G01X340234D01*
X361400Y375226D01*
Y387312D01*
G37*
G36*
G01X287792Y494268D02*
G03X289394Y495870I217J1385D01*
G02X289535Y496301I494J77D01*
G01X292704Y499470D01*
X310084D01*
X349170Y538556D01*
Y574894D01*
X348800Y575264D01*
Y623406D01*
X349974Y624580D01*
X376860D01*
G02X377360Y624080I0J-500D01*
G01Y582826D01*
X380650Y579536D01*
Y511194D01*
X375456Y506000D01*
X353799D01*
X353751Y506009D01*
G03X353169I-291J-1473D01*
G01X353121Y506000D01*
X347266D01*
X314700Y473434D01*
Y472923D01*
X314645Y472815D01*
G03Y471441I1335J-687D01*
G01X314700Y471333D01*
Y438962D01*
X314635Y438847D01*
G03Y437361I1305J-743D01*
G01X314700Y437246D01*
Y420954D01*
X307476Y413730D01*
X267284D01*
X265220Y415794D01*
Y434346D01*
X267534Y436660D01*
X276724D01*
X279450Y439386D01*
Y443283D01*
X279607Y443528D01*
X279741Y443590D01*
G03Y446318I-629J1364D01*
G02X279450Y446772I209J454D01*
G01Y463174D01*
X279590Y463409D01*
X279710Y463475D01*
G03Y466111I-720J1318D01*
G01X279590Y466177D01*
X279450Y466412D01*
Y486216D01*
X287361Y494127D01*
G02X287792Y494268I354J-353D01*
G37*
G36*
G01X432747Y642620D02*
G02X433230Y642250I0J-500D01*
G03X436069Y642065I1451J389D01*
G02X436673Y642353I462J-191D01*
G03X437925Y642538I427J1440D01*
G01X438050Y642620D01*
X474916D01*
X480230Y637306D01*
Y594321D01*
X480132Y594189D01*
G03Y592403I1208J-893D01*
G01X480230Y592271D01*
Y574504D01*
X480150Y574380D01*
G03Y572746I1260J-817D01*
G01X480230Y572622D01*
Y554189D01*
X480142Y554061D01*
G03Y552359I1238J-851D01*
G01X480230Y552231D01*
Y503634D01*
X476856Y500260D01*
X460394D01*
X457950Y502704D01*
Y528661D01*
X458018Y528778D01*
G03Y530294I-1296J758D01*
G01X457950Y530411D01*
Y573474D01*
X450474Y580950D01*
X382064D01*
X379360Y583654D01*
Y641186D01*
X380794Y642620D01*
X392832D01*
G02X393218Y642437I-1J-500D01*
G03X395542I1162J952D01*
G01X395613Y642524D01*
X395816Y642620D01*
X432747D01*
G37*
%LPD*%
G75*
G36*
G01X434136Y385761D02*
Y368570D01*
X421981Y356415D01*
X404791D01*
X392636Y368570D01*
Y385761D01*
X404791Y397916D01*
X421981D01*
X434136Y385761D01*
G37*
G36*
G01X412041Y630699D02*
X421398Y621342D01*
X421663Y621274D01*
X421796Y621314D01*
G02X423662Y619448I425J-1441D01*
G01X423622Y619315D01*
X423690Y619050D01*
X424166Y618574D01*
Y601303D01*
X423004Y600141D01*
X407932D01*
X407682Y600391D01*
X399596D01*
X398837Y601150D01*
X398484D01*
X398231Y601403D01*
X390407D01*
X388883Y602927D01*
Y625749D01*
X393833Y630699D01*
X412041D01*
G37*
G54D48*
X434102Y311875D03*
G54D53*
X354331Y349606D03*
%LPC*%
G75*
G36*
G01X421802Y606788D02*
G03Y603898I408J-1445D01*
G02X422166Y603416I-136J-481D01*
G01Y602641D01*
G02X421666Y602141I-500J0D01*
G01X407932D01*
X407682Y601891D01*
X400218D01*
X399898Y602211D01*
Y602564D01*
X399059Y603403D01*
X391235D01*
X390883Y603755D01*
Y624921D01*
X394661Y628699D01*
X411213D01*
X422166Y617746D01*
Y607270D01*
G02X421802Y606788I-500J-1D01*
G37*
%LPD*%
G75*
G54D10*
X-294532Y1044846D03*
X-281332D03*
X-287932D03*
X-267012Y1044916D03*
X-39858Y731383D03*
X-31858D03*
X4390Y533777D03*
X13170Y372673D03*
X18340Y366452D03*
X13120Y375871D03*
X16010Y369168D03*
X21530Y368991D03*
X14140Y391826D03*
X18210Y386530D03*
X13950Y388616D03*
X13390Y397543D03*
X14240Y394866D03*
X19450Y550297D03*
X20650Y546243D03*
X20350Y555807D03*
X18960Y572061D03*
X17876Y578422D03*
X16200Y566921D03*
X21881Y595792D03*
X13510Y591939D03*
X14500Y601957D03*
X11980Y617956D03*
X15349Y614142D03*
X14550Y628297D03*
X13807Y634826D03*
X9300Y631472D03*
X9240Y638699D03*
X17071Y658951D03*
X11680Y656335D03*
X9260Y658321D03*
X14000Y658369D03*
X14170Y653991D03*
X9360Y653943D03*
X33841Y9183D03*
X23987Y12977D03*
X28104Y30414D03*
X24411Y16186D03*
X36848Y25198D03*
X28408Y26414D03*
X34149Y44149D03*
X30282Y34564D03*
X30274Y37714D03*
X36588Y32278D03*
X36567Y73145D03*
X39126Y84631D03*
X34008Y91017D03*
X36567Y107988D03*
X32260Y96899D03*
X38280Y362184D03*
X35750Y364593D03*
X33420Y367309D03*
X23860Y366275D03*
X28250Y438740D03*
X37990Y453022D03*
X28250Y472076D03*
X37990Y520218D03*
X38807Y543539D03*
X38349Y555730D03*
X33231Y556346D03*
X30672Y551245D03*
X23610Y568111D03*
X34440Y597285D03*
X28112Y591718D03*
X36930Y611082D03*
X28185Y612088D03*
X35862Y617052D03*
X30744Y617898D03*
X29964Y658951D03*
X24168Y655750D03*
X37920Y651828D03*
X45410Y21563D03*
X54860Y16952D03*
X49890Y30392D03*
X51580Y17595D03*
X42205Y21518D03*
X54800Y25547D03*
X43480Y34592D03*
X45578Y50478D03*
X44010Y55170D03*
X54981Y59420D03*
X49559Y50577D03*
X41685Y73110D03*
X54101Y74252D03*
X51340Y69181D03*
X46570Y73891D03*
X47510Y109421D03*
X54703Y122796D03*
X46811Y122928D03*
X54062Y257049D03*
X49244Y360352D03*
X40690Y359555D03*
X53340Y393132D03*
X49750Y387305D03*
X51720Y384808D03*
X50840Y395761D03*
X47820Y398827D03*
X49730Y412473D03*
X45530D03*
X52150Y414896D03*
X47900Y414660D03*
X44360Y414915D03*
X49640Y430237D03*
X45410Y430444D03*
X51350Y433695D03*
X47420Y433725D03*
X44360Y433729D03*
X51670Y462885D03*
X47590Y463876D03*
X49830Y465496D03*
X47200Y467262D03*
X49590Y469432D03*
X49625Y478472D03*
Y480972D03*
X49185Y472713D03*
X50330Y497940D03*
X53330D03*
X49645Y491804D03*
Y489304D03*
X47380Y494638D03*
X53622Y509276D03*
X53330Y506417D03*
Y503817D03*
X50330D03*
X53769Y513033D03*
X54988Y518683D03*
X49857Y520516D03*
X50630Y529281D03*
X46140Y541712D03*
X50140Y550572D03*
X39540Y538464D03*
X50870Y564008D03*
X43467Y555938D03*
X53988Y568748D03*
X49680Y579709D03*
X49620Y574212D03*
X47557Y588971D03*
X44507Y594082D03*
X40908Y589691D03*
X43850Y602797D03*
X39370Y600956D03*
X42950Y612487D03*
X50270Y627793D03*
X48540Y624953D03*
X52230Y614907D03*
X51051Y619407D03*
X48060Y621229D03*
X47480Y616848D03*
X50170Y636895D03*
X51038Y643928D03*
X46890Y633564D03*
X53751Y652029D03*
X44640Y651029D03*
X40980Y656396D03*
X49720Y668412D03*
X59524Y25922D03*
X56610Y20553D03*
X66981Y59390D03*
X62981Y59440D03*
X57040Y73421D03*
X64190Y72841D03*
X61760Y107321D03*
X55230Y112521D03*
X63900Y112081D03*
X64309Y141882D03*
X68756Y167695D03*
X56190Y170026D03*
X59640Y161376D03*
X57257Y180712D03*
X67853Y180744D03*
X68690Y175589D03*
X55963Y199565D03*
X68930Y197193D03*
X66570Y189983D03*
X57749Y204326D03*
X56383Y218543D03*
X68830Y215817D03*
X63720Y228683D03*
X56936Y223944D03*
X56287Y242872D03*
X63718Y239030D03*
X61945Y267579D03*
X66818Y297483D03*
X57994Y287655D03*
X57624Y366105D03*
X66747Y466363D03*
X64050Y465689D03*
X61183Y465314D03*
X61357Y483392D03*
Y480892D03*
Y477892D03*
X61188Y487117D03*
X56330Y497940D03*
X58830D03*
X61676Y502656D03*
Y500156D03*
X61188Y489617D03*
Y492117D03*
X55982Y494543D03*
X64480Y501596D03*
X65438Y510666D03*
X61033Y510705D03*
X61003Y515110D03*
X65478D03*
X56148Y530809D03*
X62253Y522589D03*
X67369Y522993D03*
X70696Y527237D03*
X67260Y546688D03*
X65900Y566403D03*
X66181Y562149D03*
X63930Y560181D03*
X66262Y553344D03*
X65989Y578115D03*
X66036Y574901D03*
X63670Y576040D03*
X57710Y572918D03*
X57070Y580074D03*
X69766Y582525D03*
X57440Y585607D03*
X68630Y599945D03*
X63300Y621755D03*
X61205Y623870D03*
X63570Y613914D03*
X63610Y618917D03*
X61205Y628870D03*
X63490Y630693D03*
X62160Y644091D03*
X59390Y642906D03*
X56240Y630081D03*
X59530Y631704D03*
X63650Y646957D03*
X61600Y653611D03*
X66880Y761625D03*
X59260Y779815D03*
X58840Y783097D03*
X62290Y779629D03*
X67660Y779452D03*
X62730Y782694D03*
X66860Y782716D03*
X60370Y776861D03*
X64790Y776777D03*
X56500Y789667D03*
X79360Y46044D03*
X82065Y73224D03*
X80845Y106859D03*
X76880Y126528D03*
X72890Y154349D03*
X76030Y156152D03*
X81030Y172605D03*
X78850Y157866D03*
X85010Y171679D03*
X71510Y164548D03*
X74470Y175666D03*
X82553Y185431D03*
X82030Y191733D03*
X75236Y188946D03*
X75359Y201109D03*
X85876Y218939D03*
X78190Y214642D03*
X86172Y213852D03*
X75560Y218513D03*
X73870Y205758D03*
X72150Y225148D03*
X78614Y229920D03*
X79217Y232861D03*
X83390Y235665D03*
X79142Y237920D03*
X77239Y260814D03*
X81210Y261337D03*
X81165Y257717D03*
X79544Y267579D03*
X78373Y276029D03*
X78220Y281745D03*
X78207Y279092D03*
X72190Y297395D03*
X82368Y297135D03*
X72368Y287906D03*
X82560Y288099D03*
X82600Y285426D03*
X77368Y299206D03*
X73917Y385722D03*
X74058Y389621D03*
X83084D03*
X74031Y393857D03*
X73868Y397913D03*
X83245D03*
X85951Y410263D03*
X74291Y486665D03*
X83455Y489485D03*
Y491985D03*
X85955Y489485D03*
Y491985D03*
X83455Y494485D03*
X85955D03*
X83536Y498308D03*
X81635Y517104D03*
Y513104D03*
X85346Y512295D03*
X73057Y515286D03*
X72635Y508991D03*
X81491Y533191D03*
X82031Y523928D03*
X72216Y540493D03*
X80318Y544311D03*
X81585Y536382D03*
X80318Y541026D03*
X73130Y601599D03*
X73180Y611184D03*
X75380Y608914D03*
Y603914D03*
X80630Y689682D03*
X82847Y716068D03*
X82736Y791695D03*
Y788695D03*
X70925D03*
Y791695D03*
X97830Y66508D03*
X98531Y121340D03*
X90878Y177967D03*
X90905Y199733D03*
X101449Y194368D03*
X86560Y205852D03*
X96168Y231618D03*
X98700Y234650D03*
X96990Y223043D03*
X101020Y223348D03*
X93200Y300734D03*
X99968Y367705D03*
X95968Y367814D03*
X95951Y376661D03*
X98410Y421908D03*
X98470Y418834D03*
X101650Y428745D03*
Y425552D03*
Y433296D03*
Y436075D03*
X101590Y446203D03*
X101650Y443038D03*
X86726Y501997D03*
X88563Y491984D03*
Y489484D03*
Y494484D03*
X86695Y498180D03*
X91458Y511853D03*
X87721Y505817D03*
X92422Y531081D03*
X95660Y531362D03*
X98803Y531597D03*
X97268Y537055D03*
X97366Y542897D03*
X98370Y619252D03*
X94070Y618986D03*
Y613841D03*
X97790Y613797D03*
X96200Y616325D03*
X95350Y644088D03*
X95310Y647481D03*
X98480Y646217D03*
X98410Y648878D03*
Y680541D03*
X100223Y733207D03*
X89810Y765905D03*
X97390Y766435D03*
X98590Y782494D03*
X97180Y786472D03*
X94547Y788695D03*
Y791695D03*
X112386Y71874D03*
X115628Y104405D03*
X111220Y160923D03*
X106090Y167615D03*
X112530Y186363D03*
X106760Y175370D03*
X114920Y179082D03*
X108910Y193194D03*
X106517Y210796D03*
X104550Y262359D03*
X104270Y265662D03*
X110230Y360735D03*
X103151Y373340D03*
X110230Y363235D03*
X117030Y389978D03*
X110490Y397362D03*
X116960Y394023D03*
X103750Y402740D03*
X103810Y405876D03*
X103870Y399604D03*
X108235Y401017D03*
X111120Y401084D03*
X115727Y405844D03*
X113412Y404826D03*
X113504Y407673D03*
X107531Y394023D03*
X114207Y417910D03*
Y414910D03*
X105670Y411262D03*
X117980Y451981D03*
X118020Y455079D03*
X114072Y480964D03*
X115516Y485696D03*
X110400Y502223D03*
X110436Y499681D03*
X110472Y496888D03*
X113337Y502080D03*
X113372Y496888D03*
X113301Y499574D03*
X117026Y488316D03*
X108026Y492500D03*
X114372Y518898D03*
X109972Y509321D03*
X112575Y532934D03*
X109972Y519508D03*
X113912Y541144D03*
X114005Y544358D03*
X112627Y536697D03*
X109640Y611890D03*
X109410Y621425D03*
X109500Y616724D03*
X109260Y644687D03*
Y648989D03*
X117790Y667235D03*
X115748Y716275D03*
X106358Y785790D03*
X102421Y782191D03*
X110295Y785734D03*
Y782191D03*
X116370Y785941D03*
X104300Y773100D03*
X106650Y779581D03*
X102421Y785938D03*
X114232Y791695D03*
Y788695D03*
X129860Y14571D03*
X130195Y19162D03*
X131474Y43439D03*
X131068Y76588D03*
X126220Y80364D03*
Y83291D03*
X125480Y91163D03*
X132400Y88153D03*
X129580Y86837D03*
X129780Y92580D03*
X124150Y94643D03*
X128330Y98360D03*
X130350Y130400D03*
Y134167D03*
X126460Y250160D03*
X129650Y250414D03*
X126570Y256194D03*
X129650Y255414D03*
X129660Y279890D03*
X130310Y269174D03*
X130324Y272096D03*
Y277096D03*
X123160Y287060D03*
X129610Y287115D03*
X123960Y283696D03*
X128960D03*
X125050Y384546D03*
X122120Y386736D03*
X126300Y390369D03*
X122729Y398001D03*
X127729D03*
X125229D03*
X128226Y413925D03*
X125726D03*
X123226D03*
X129028Y425593D03*
X121080Y460060D03*
X124040Y459746D03*
X127060Y460040D03*
X126377Y466738D03*
X126260Y470267D03*
X121360Y472028D03*
X118720Y471989D03*
X126072Y480864D03*
X130794Y493910D03*
X133731D03*
X127705Y489431D03*
X125105D03*
X119326Y489706D03*
X121968Y488481D03*
X122018Y516353D03*
X118124Y510811D03*
X133138Y510114D03*
X121644Y509398D03*
X130596Y510042D03*
X124652Y509398D03*
X130703Y512549D03*
X130844Y515128D03*
X128087Y513874D03*
X124279Y523691D03*
X132960Y550005D03*
X125340Y558090D03*
X120300Y572512D03*
X133590Y588438D03*
X130790Y595613D03*
X128240Y666583D03*
X120909Y674490D03*
X132190Y662616D03*
X121070Y670509D03*
X132050Y671817D03*
X129607Y686735D03*
X133607Y686699D03*
X130260Y679836D03*
X132438Y704733D03*
X133490Y695470D03*
X126220Y720949D03*
X120357Y738889D03*
X132334Y732982D03*
X120322Y742187D03*
X123518Y742030D03*
X119900Y754021D03*
X125600Y759000D03*
X125960Y785699D03*
X120090Y780618D03*
X130850Y782456D03*
X118169Y783857D03*
X130660Y785601D03*
X127290Y781982D03*
X122720Y785051D03*
X137500Y25494D03*
X141490Y19267D03*
X137872Y29551D03*
X147427Y30367D03*
X146380Y20345D03*
X147461Y38078D03*
X147497Y42983D03*
X139931Y40842D03*
X139932Y35310D03*
X145210Y60154D03*
X149157Y60010D03*
X135050Y53493D03*
X137540Y58255D03*
X143857Y51943D03*
X149025Y51720D03*
X146558Y74863D03*
X135290Y87664D03*
X140350Y81347D03*
X135640Y134167D03*
X135590Y130449D03*
X147570Y249033D03*
X147160Y242219D03*
X144400Y244061D03*
Y247561D03*
X148330Y258806D03*
X141682Y269829D03*
X143150Y281123D03*
X145200Y276468D03*
X138930Y278965D03*
X148350Y281769D03*
X134540Y267786D03*
X137925Y290987D03*
X137990Y296735D03*
X139950Y293835D03*
X136130Y305640D03*
X137091Y301799D03*
X149020Y303498D03*
X145720Y311336D03*
X135730Y314543D03*
X134768Y319043D03*
X135224Y323543D03*
X146100D03*
X145580Y316836D03*
X136506Y332193D03*
X144058Y376025D03*
X137889Y403348D03*
X141800Y404481D03*
X141847Y401820D03*
X135088Y405060D03*
X135181Y402121D03*
X145295Y404388D03*
X145284Y401507D03*
X135507Y421367D03*
X142239Y422346D03*
X139395Y425090D03*
X138437Y435930D03*
Y438430D03*
X147820Y441929D03*
X147576Y445279D03*
Y447779D03*
Y450279D03*
X138437Y440930D03*
X135300Y468444D03*
X146240Y472111D03*
X139310Y478102D03*
X136470Y481994D03*
X139365Y516636D03*
X139402Y513707D03*
X149477Y532733D03*
X144120Y547577D03*
X146920Y547677D03*
X145020Y576001D03*
X145550Y588088D03*
X149050Y588044D03*
X141260Y588175D03*
X141190Y597685D03*
X145880Y584125D03*
X144710Y598135D03*
X136420Y599352D03*
X147753Y627557D03*
X145750Y630254D03*
X148140Y660112D03*
X148487Y676041D03*
X148200Y669205D03*
X140110Y675907D03*
X147750Y687539D03*
X143823Y682907D03*
X134450Y682978D03*
X139158Y686725D03*
X135280Y679212D03*
X138726Y696707D03*
X138198Y712628D03*
X134777Y738726D03*
Y734726D03*
X134753Y726161D03*
X137070Y728012D03*
X144631Y735955D03*
X134720Y742382D03*
X147290Y744113D03*
X145040Y740741D03*
X139600Y781281D03*
X135470Y781697D03*
X135610Y784521D03*
X139680Y784596D03*
X149450Y780429D03*
X146150Y783820D03*
X145570Y780580D03*
X141791Y788695D03*
Y791695D03*
X150787Y9246D03*
X158181Y11978D03*
X153863Y15176D03*
X164139Y13027D03*
X154592Y21173D03*
X157877Y30674D03*
X152810Y29921D03*
X158165Y21300D03*
X150592Y20974D03*
X152412Y38112D03*
X152366Y42983D03*
X156255Y45743D03*
X159861Y36134D03*
X160731Y41038D03*
X162350Y42984D03*
X152789Y53124D03*
X157659Y47891D03*
X157010Y58963D03*
X164550Y61239D03*
X156440Y74863D03*
X161221Y89447D03*
X151618Y83343D03*
X160040Y108844D03*
X164280Y101810D03*
X162130Y129344D03*
X164490Y127110D03*
X159190Y127781D03*
X163518Y243987D03*
X162317Y249877D03*
X152990Y248096D03*
X157690Y249918D03*
X161918Y254287D03*
X160449Y259605D03*
X154546Y256986D03*
X162484Y276599D03*
X152634Y276809D03*
X158583Y285548D03*
X161918Y293869D03*
X161767Y287242D03*
X149721Y292987D03*
X152733Y288517D03*
X158076Y290635D03*
X162181Y303075D03*
X161687Y310355D03*
X154581Y308767D03*
X162063Y327940D03*
X162017Y324389D03*
X159564Y328013D03*
X161513Y317143D03*
X151230Y330164D03*
X150918Y318134D03*
X159285Y336220D03*
X150510Y336306D03*
X156448Y336629D03*
X162071Y336947D03*
X164418Y348187D03*
X152058Y376016D03*
X160058Y375818D03*
X150524Y382808D03*
X165290Y385948D03*
X151820Y385554D03*
X150902Y379714D03*
X160886Y380294D03*
X160710Y384044D03*
X161640Y403286D03*
X162940Y406188D03*
X161577Y436834D03*
X161563Y432521D03*
X154370Y449930D03*
X151145Y469456D03*
X150547Y459363D03*
X163377Y484538D03*
X152554Y494027D03*
X158406Y500016D03*
X162335Y512456D03*
X159196Y515612D03*
X159179Y521893D03*
X154126Y524411D03*
X154475Y530422D03*
X159180Y528227D03*
X162335Y543954D03*
X159185Y537654D03*
X162336Y550253D03*
X155109Y561153D03*
X164259Y557273D03*
X154140Y577815D03*
X158430Y568437D03*
X161280Y581585D03*
X151900Y590454D03*
X156480Y583315D03*
X153527Y597138D03*
X150380Y602885D03*
X153712Y610917D03*
X153330Y599935D03*
X153422Y603043D03*
X153955Y620760D03*
X157963Y643289D03*
Y633735D03*
X162668Y631897D03*
X162530Y643235D03*
Y636435D03*
X151915Y675068D03*
X155957Y674813D03*
X160112Y674990D03*
X165012Y675887D03*
X164812Y662579D03*
X151567Y687579D03*
X155650Y681515D03*
X161994Y678445D03*
X159590Y683050D03*
X157287Y678138D03*
X165167Y681311D03*
X152222Y678394D03*
X160101Y687962D03*
X163018Y684381D03*
X164092Y688014D03*
X150840Y682436D03*
X149860Y726626D03*
X154970Y736966D03*
X161981Y730784D03*
X158881D03*
X162640Y743927D03*
X158970D03*
X154400Y744337D03*
X155230Y740259D03*
X163138Y778565D03*
X160480Y777583D03*
X155170Y780656D03*
X164630Y781222D03*
X153320Y783499D03*
X160320Y786346D03*
X149810Y783858D03*
X179235Y7369D03*
X171310Y12450D03*
X171666Y7449D03*
X175280Y12401D03*
X174166Y7449D03*
X166639Y13027D03*
X168961Y27073D03*
X165959Y27133D03*
X173110Y26877D03*
X180907Y27544D03*
X176090Y26906D03*
X180159Y40661D03*
X165336Y46126D03*
X177224Y49101D03*
X174724D03*
X177224Y51601D03*
X174724D03*
X172224Y49101D03*
Y54101D03*
X177224D03*
X174724D03*
X172224Y51601D03*
X169149Y50968D03*
X168040Y61462D03*
X177757Y88271D03*
X168308Y88412D03*
X177733Y91967D03*
X167383Y93147D03*
X180990Y108770D03*
X177210Y97657D03*
X165690Y98835D03*
X171950Y105105D03*
X168850Y99251D03*
X169510Y106579D03*
X173900Y97662D03*
X177680Y101764D03*
X174710Y105699D03*
X167127Y120603D03*
X174213Y120569D03*
X177763Y121057D03*
X168170Y123367D03*
X173170D03*
X180510Y233307D03*
X178040Y228978D03*
X174138Y243873D03*
X171320Y243601D03*
X167467Y243242D03*
X167483Y239914D03*
X177891Y249324D03*
X171668Y256287D03*
X175756Y257668D03*
X173263Y262589D03*
X176301Y262624D03*
X167322Y255855D03*
X167698Y260617D03*
X178929Y262244D03*
X175110Y260412D03*
X175118Y274287D03*
X170617Y267326D03*
X175318Y278687D03*
X170510Y275522D03*
X178025Y279018D03*
X174078Y271435D03*
X170829Y271452D03*
X178941Y270160D03*
X177470Y294933D03*
X180254Y295023D03*
X175162Y293934D03*
X175659Y286984D03*
X178810Y287263D03*
X174148Y289289D03*
X176037Y309845D03*
X180254Y310663D03*
X178812Y324259D03*
X180342Y316469D03*
X175330Y318552D03*
X166189Y335285D03*
X167383Y341306D03*
X177359Y332553D03*
X174876Y336549D03*
X168110Y350642D03*
X177604Y355155D03*
X177720Y352522D03*
X177029Y347811D03*
X177672Y358103D03*
X176058Y376568D03*
X168058Y376035D03*
X167951Y380551D03*
X175290Y389582D03*
X174500Y383383D03*
X178660Y388418D03*
X171934Y386364D03*
X175155Y380727D03*
X180430Y392969D03*
X175663Y386424D03*
X176371Y404721D03*
X180440Y398056D03*
X172760Y406540D03*
X170506Y424127D03*
X175993Y414924D03*
X167527Y420268D03*
X179562Y424001D03*
X173381Y424005D03*
X178232Y430642D03*
X178217Y435317D03*
X173151Y427552D03*
X170683Y436834D03*
X170361Y428595D03*
X172944Y448387D03*
X170444D03*
X177525Y451946D03*
X180125D03*
X178961Y448138D03*
X176220Y448247D03*
X171616Y467804D03*
X179857Y477790D03*
X169728Y487664D03*
X168189Y514331D03*
X178085Y512456D03*
X173252Y515693D03*
X165707Y506156D03*
X172087Y510536D03*
X169615Y519216D03*
X178094Y531365D03*
X166297Y532416D03*
X169491Y529702D03*
X166837Y523486D03*
X174395Y527975D03*
X171606Y527511D03*
X168243Y542706D03*
X174930Y547106D03*
X169157Y548676D03*
X169293Y562358D03*
X173163Y551903D03*
X169444Y558757D03*
X167105Y552882D03*
X178083Y553402D03*
X172889Y562710D03*
X171053Y569411D03*
X175330Y578535D03*
X166930Y578435D03*
X172430Y584035D03*
X177830Y583535D03*
X166570Y583874D03*
X166605Y587860D03*
X179532Y600437D03*
X173432D03*
X165832Y600337D03*
Y606037D03*
Y613137D03*
X172532Y619537D03*
X178632Y619437D03*
X165832D03*
X179120Y639615D03*
X169930Y635329D03*
X172510Y639771D03*
X167530Y631935D03*
X174479Y631986D03*
X177038Y647135D03*
X166388Y647435D03*
X171180Y652009D03*
X171270Y655650D03*
X179180Y675205D03*
X174761Y663816D03*
X167810Y668131D03*
X168645Y688064D03*
X165628Y691289D03*
X167315Y684943D03*
X178982Y688631D03*
X171180Y683815D03*
X178278Y705976D03*
Y701976D03*
Y697976D03*
X169268Y705304D03*
X169396Y701006D03*
X169268Y697399D03*
X169619Y693335D03*
X178278Y709976D03*
X180820Y717914D03*
X171154Y715673D03*
X169531Y710542D03*
X175463Y720245D03*
X171689Y728920D03*
X165599Y730476D03*
X174954Y728404D03*
X177920Y739302D03*
X167568Y743335D03*
X177224Y777765D03*
X169350Y785470D03*
X172600Y780150D03*
X169860Y782086D03*
X167350Y778074D03*
X173287Y791695D03*
Y788695D03*
X189235Y7369D03*
X191735D03*
X181735D03*
X194825Y10196D03*
X194861Y12952D03*
X183407Y27544D03*
X188634Y27860D03*
X191596Y27620D03*
X184843Y88467D03*
X191930Y88507D03*
X184928Y91847D03*
X189928D03*
X196653Y91837D03*
X196000Y95568D03*
X195473Y108767D03*
X184170Y95213D03*
X186060Y100103D03*
X196493Y105637D03*
X183013Y98813D03*
X190100Y99701D03*
X188203Y104567D03*
X196010Y125188D03*
X186730Y121202D03*
X194463Y122631D03*
X188821Y232784D03*
X184050Y230139D03*
X183550Y235060D03*
X193677Y243855D03*
X189192Y243061D03*
X184318Y247612D03*
X188899Y240208D03*
X195126Y249955D03*
X184296Y241098D03*
X188899Y236808D03*
X194056Y256697D03*
X193735Y265857D03*
X188442Y252643D03*
X184829Y259139D03*
X181176Y257643D03*
X188658Y256870D03*
X184117Y264852D03*
X181602Y262656D03*
X186873Y263697D03*
X185798Y256760D03*
X186873Y260697D03*
X194693Y259197D03*
Y262197D03*
X190918Y277687D03*
X185991Y279041D03*
X186118Y270787D03*
X183440Y269816D03*
X194205Y271034D03*
X191860Y270148D03*
X183198Y278034D03*
X183698Y285693D03*
X193557Y294428D03*
X187812Y286352D03*
X184812Y292979D03*
X186254Y295023D03*
X192298Y286183D03*
X194771Y302176D03*
X193812Y308619D03*
X195254Y310663D03*
X184754Y302843D03*
X186254Y310663D03*
X183254D03*
X193313Y325492D03*
X186296Y326366D03*
X186350Y317116D03*
X196476Y317042D03*
X183228Y317023D03*
X193957Y317064D03*
X191159Y317171D03*
X190557Y325701D03*
X187404Y343998D03*
X192293Y340792D03*
X185195Y332852D03*
X184367Y337792D03*
X192230Y337322D03*
X192040Y333606D03*
X186925Y355812D03*
X192519Y352761D03*
X186908Y352760D03*
X184058Y376479D03*
X195420Y372406D03*
X194231Y390267D03*
X184927Y383876D03*
X192681Y377554D03*
X193590Y383383D03*
X185074Y380726D03*
X194330Y396425D03*
X192676Y402961D03*
X196273Y403152D03*
X182771Y424013D03*
X185271D03*
X182771Y421513D03*
X185271D03*
X190700Y418325D03*
X182132Y418327D03*
X182877Y430662D03*
X182879Y435312D03*
X192527Y429049D03*
X189077Y438281D03*
X192069Y444852D03*
X184523Y441915D03*
X181923Y445044D03*
Y442544D03*
X185747Y487664D03*
X193500Y489796D03*
X181231Y512455D03*
X184843Y533995D03*
X188640Y530667D03*
X191457Y531553D03*
X193466Y546886D03*
X186841Y545372D03*
X181232Y553402D03*
X181491Y557436D03*
X188654Y573395D03*
X193080Y581235D03*
X191500Y571956D03*
X182480Y566819D03*
X196740Y589735D03*
X181330Y587535D03*
X185032Y606737D03*
X184932Y600537D03*
X185032Y612937D03*
X184932Y619437D03*
X192130Y632235D03*
X184748Y639687D03*
X182480Y634585D03*
X191480Y639135D03*
X182353Y631612D03*
X188200Y672526D03*
X196463Y685036D03*
X182163Y684555D03*
X185993Y682670D03*
X191542Y691925D03*
X194508Y704476D03*
X187798Y704513D03*
X181744Y694829D03*
X181950Y698191D03*
X190375Y695624D03*
X185440Y712499D03*
X196144Y712602D03*
X187744Y708356D03*
X191930Y712624D03*
X188566Y722353D03*
X183566D03*
X193566Y722333D03*
X196079Y723943D03*
X194440Y735623D03*
X189940Y735681D03*
X185440D03*
X182674Y730521D03*
X191150Y724108D03*
X186164Y724134D03*
X192949Y771020D03*
X182500Y780786D03*
X189770Y778082D03*
X204785Y13762D03*
X204978Y10605D03*
X201849Y15292D03*
X198577Y15374D03*
X199016Y88434D03*
X206103Y88207D03*
X204003Y91247D03*
X202560Y107797D03*
X210203Y108457D03*
X206273Y98364D03*
X200480Y97687D03*
X212423Y104957D03*
X208908Y96975D03*
X205903Y101477D03*
X199993Y103637D03*
X210623Y121267D03*
X207070Y179744D03*
X207154Y175212D03*
X207041Y184502D03*
X207070Y188978D03*
X212020Y234359D03*
X205535Y234497D03*
Y228682D03*
X211935Y230585D03*
X198296Y232699D03*
X211935Y244085D03*
X198685Y240785D03*
X211935Y237385D03*
Y240785D03*
X205566Y243497D03*
X205271Y240209D03*
X198685Y237385D03*
Y244085D03*
X211028Y255696D03*
X210333Y265197D03*
X208129Y257519D03*
X206144Y252477D03*
X208289Y263639D03*
X210305Y259330D03*
Y262289D03*
X201994Y261248D03*
X200977Y256305D03*
X202402Y263713D03*
X200469Y259139D03*
X201518Y265990D03*
X208226Y269697D03*
X201667Y274542D03*
X199509Y278094D03*
X210303Y268227D03*
X206299Y281098D03*
X210303Y271227D03*
X203149Y281098D03*
X201518Y268887D03*
X206299Y290548D03*
X206319Y296863D03*
X203149Y290548D03*
X206299Y293698D03*
Y312598D03*
Y306298D03*
Y303148D03*
X209449Y312598D03*
X203166Y312577D03*
X202525Y299358D03*
X209300Y322800D03*
X207310Y330149D03*
X206299Y315748D03*
X203058Y315593D03*
X200211Y321446D03*
X200572Y323920D03*
X208000Y325200D03*
X208700Y328000D03*
X200590Y327615D03*
X208485Y332356D03*
X200905Y333776D03*
X201489Y336207D03*
Y339107D03*
X197243Y344518D03*
X206817Y358874D03*
X207274Y353124D03*
X198987Y353137D03*
X206657Y356116D03*
X202823Y376922D03*
X197938Y376839D03*
X206973Y361900D03*
X200439Y390168D03*
X203880Y385272D03*
X205790Y387003D03*
X200488Y396425D03*
X201267Y403294D03*
X210880Y402359D03*
X206380Y402201D03*
X200039Y448750D03*
Y451350D03*
X197809Y469953D03*
X204584Y462478D03*
X197161Y465628D03*
X200434Y478345D03*
X200459Y487253D03*
X208710Y500856D03*
X211379Y501904D03*
X211609Y516553D03*
X205257Y528822D03*
X211287Y528547D03*
X212342Y536729D03*
X199539Y537112D03*
X204309Y539953D03*
X205286Y551130D03*
X202486D03*
X211240Y572893D03*
X210040Y576893D03*
X201510Y576885D03*
X197730Y572893D03*
X197709Y567464D03*
X210790Y566926D03*
X209940Y584893D03*
X197230Y595335D03*
X198890Y584105D03*
X207178Y591595D03*
X211760Y610915D03*
X207476Y608936D03*
X207010Y602472D03*
X196907Y605012D03*
X197030Y598535D03*
X204024Y604135D03*
Y609135D03*
X208904Y611515D03*
X200380Y629085D03*
X199786Y618893D03*
X211862Y617709D03*
X202510Y624005D03*
X197230Y615435D03*
X208904Y616515D03*
X197480Y639815D03*
X203065Y638700D03*
X205221Y630886D03*
X200910Y659735D03*
X209238Y674373D03*
X202450Y663633D03*
X199510Y663158D03*
X205410Y661200D03*
X211560Y670575D03*
X210824Y692266D03*
X199590Y682868D03*
X197582Y703474D03*
X200692Y704081D03*
X199350Y692724D03*
X211236Y695586D03*
X197243Y697899D03*
X210023Y712842D03*
X201663Y712694D03*
X198940Y712499D03*
X198566Y722353D03*
X209017Y722344D03*
X203611Y722303D03*
X205440Y712510D03*
X211897Y723870D03*
X212440Y735829D03*
X198940Y735681D03*
X207940D03*
X203440D03*
X205883Y724373D03*
X200817Y724180D03*
X199760Y763929D03*
X202050Y784919D03*
X206210Y771577D03*
X212350Y773283D03*
X200846Y788695D03*
Y791695D03*
X225990Y21219D03*
X221990D03*
X222290Y45504D03*
X226290D03*
X221310Y51103D03*
X225310D03*
X221600Y66317D03*
X225600D03*
X213190Y88414D03*
X220276Y88440D03*
X214573Y93771D03*
X215773Y90147D03*
X222983Y91587D03*
X220200Y93561D03*
X226620Y89385D03*
X219095Y108675D03*
X217040Y103121D03*
X214320Y101978D03*
X220983Y106174D03*
X213908Y96975D03*
X219510Y101338D03*
X226713Y122007D03*
X228138Y125802D03*
X226010Y233542D03*
X217135Y230585D03*
Y244085D03*
X226010Y240342D03*
X217135Y240785D03*
Y237385D03*
X219772Y252659D03*
X215761Y252833D03*
X224794Y256754D03*
X218153Y260697D03*
Y263697D03*
X223929Y263639D03*
X216512Y258490D03*
X225973Y262197D03*
X216109Y265139D03*
Y262139D03*
X218508Y256664D03*
X225973Y259197D03*
X225199Y281098D03*
X216109Y274139D03*
X212599Y281098D03*
X224357Y273228D03*
X216109Y271139D03*
X215749Y281098D03*
X213138Y274187D03*
X212599Y290548D03*
X225199Y287398D03*
X212599Y293698D03*
X222049Y290548D03*
X215749Y293698D03*
Y287398D03*
X225199Y309448D03*
Y299998D03*
Y303148D03*
X222049Y309448D03*
X212599Y299998D03*
Y303148D03*
X222049Y312598D03*
X218899Y309448D03*
X222049Y303148D03*
X218899Y299998D03*
Y303148D03*
X218947Y312617D03*
X215100Y322700D03*
X217129Y327207D03*
X215085Y325649D03*
X212600Y319100D03*
X217129Y324207D03*
X224949Y328707D03*
X225199Y315748D03*
X224585Y322992D03*
X224711Y325922D03*
X217129Y336207D03*
X217067Y339542D03*
X217129Y333207D03*
X223010Y344242D03*
X223166Y338842D03*
X222911Y333155D03*
X224996Y334617D03*
X223095Y336241D03*
X221280Y340579D03*
X228057Y352837D03*
X222777Y353066D03*
X214888Y352909D03*
X222974Y356134D03*
X214657Y356205D03*
X214007Y362701D03*
X222225Y364031D03*
X227745Y368007D03*
X223561Y385108D03*
X214008Y385165D03*
X221438Y390655D03*
X214786Y388603D03*
X218090Y390891D03*
X216633Y384989D03*
X215120Y399654D03*
X214406Y395539D03*
X223085Y401702D03*
X213710Y402237D03*
X224730Y418003D03*
X221406Y436560D03*
X227816Y442675D03*
X218483Y442550D03*
X221858Y442300D03*
X225024Y442467D03*
X226276Y460704D03*
X213994Y466054D03*
X222419Y479933D03*
X218040Y473853D03*
X223786Y476638D03*
X226255Y472579D03*
X216209Y488853D03*
X213209D03*
X224209Y494928D03*
X227284Y502591D03*
X224209Y491853D03*
X217609Y516353D03*
X219328Y528823D03*
X223376Y523322D03*
X215946Y544202D03*
X221591Y563371D03*
X223561Y561475D03*
X218950Y565589D03*
X223453Y578087D03*
X216590Y570850D03*
X220428Y580271D03*
X227100Y580916D03*
X218859Y593093D03*
X225100Y597453D03*
X219960Y596373D03*
X219296Y604811D03*
X219960Y601373D03*
X215699Y625977D03*
X215985Y633977D03*
X216107Y637977D03*
X215948Y629977D03*
X221129Y642363D03*
X228290Y629893D03*
X215768Y671993D03*
X218240Y674433D03*
X212635Y665604D03*
X224289Y680081D03*
X224360Y684366D03*
X213365Y692151D03*
X224060Y690317D03*
X224336Y687758D03*
X223707Y695436D03*
X220580Y692876D03*
X223741Y700554D03*
X221340Y697995D03*
X226610Y713482D03*
X217530Y715305D03*
X221320Y720698D03*
X213310Y719064D03*
X222710Y713706D03*
X216820Y723301D03*
X227650Y720791D03*
X224410Y719970D03*
X216940Y736063D03*
X221440Y735934D03*
X225940Y724061D03*
Y733671D03*
Y736437D03*
X218270Y785657D03*
X220960Y778561D03*
X226670Y773299D03*
X220532Y788695D03*
Y791695D03*
X212658D03*
Y788695D03*
X241990Y21219D03*
X229990D03*
X242290Y45504D03*
X230290D03*
X229310Y51103D03*
X233290Y51045D03*
X237310Y50983D03*
X241310D03*
X237600Y66317D03*
X241600D03*
X229600D03*
X233600D03*
X236360Y93931D03*
X236812Y88698D03*
X229725Y88719D03*
X235113Y91307D03*
X231013Y91547D03*
X243373Y88767D03*
X239563Y92077D03*
X243730Y103057D03*
X240355Y108757D03*
X239500Y100925D03*
X231910Y105731D03*
X235190Y96905D03*
X230643Y108497D03*
X234243Y100156D03*
X233083Y94817D03*
X237773Y103607D03*
X242913Y106157D03*
X233268Y121742D03*
X233138Y125802D03*
X232948Y234047D03*
X236710Y244042D03*
X242460Y237591D03*
X237654Y249719D03*
X231710Y243642D03*
Y240242D03*
X231749Y265139D03*
X239569Y257639D03*
X241613Y262197D03*
X239569Y266639D03*
X241613Y259197D03*
X237594Y252754D03*
X239569Y263639D03*
X233793Y263697D03*
X231749Y262139D03*
X233793Y260697D03*
X239569Y260639D03*
X231749Y259139D03*
X240910Y274742D03*
X233793Y269697D03*
X239569Y269639D03*
X232118Y271587D03*
X241613Y271197D03*
Y268197D03*
X228821Y274197D03*
X231648Y274243D03*
X237799Y290548D03*
Y284248D03*
X231499Y287398D03*
X240949Y296848D03*
X237800Y299998D03*
X231499Y309448D03*
X237799Y303148D03*
X234649D03*
X237799Y306298D03*
X240925Y306257D03*
X240949Y299998D03*
Y303148D03*
X241258Y319123D03*
X230725Y325649D03*
X238545Y327149D03*
X240374Y328960D03*
X240511Y325517D03*
X240692Y344204D03*
X233055Y339936D03*
X230725Y331649D03*
X238548Y333149D03*
X230725Y334547D03*
X240598Y334642D03*
X240218Y338010D03*
X231144Y338225D03*
X238560Y336136D03*
X232769Y333207D03*
X232804Y336181D03*
X239290Y340428D03*
X233697Y353961D03*
X238084Y355992D03*
X228419Y356855D03*
X233635Y357082D03*
X230010Y373300D03*
X237578Y369584D03*
X233136Y367070D03*
X243078Y368384D03*
X231257Y362218D03*
X243940Y390885D03*
X236687Y385234D03*
X232172Y388814D03*
X228729Y385227D03*
X241451Y392147D03*
X236412Y387722D03*
X231223Y391424D03*
X239546Y390528D03*
X236430Y393470D03*
X232647Y396011D03*
X228906Y424560D03*
X228713Y416525D03*
Y419525D03*
X240599Y440053D03*
X231870Y439511D03*
X228906Y433560D03*
Y427560D03*
Y436560D03*
X231885Y442252D03*
X231461Y462591D03*
X243471Y460292D03*
X238430Y460338D03*
X234209Y480953D03*
X228604Y479682D03*
X233626Y512040D03*
X236776Y534087D03*
X233626Y524639D03*
X236776Y540386D03*
X235307Y566357D03*
X242915Y576539D03*
X243209Y574018D03*
X239269Y597128D03*
X229809Y583627D03*
X229269Y597682D03*
X242830Y597415D03*
X242796Y589749D03*
X236780Y628738D03*
X229199Y642180D03*
X243693Y632254D03*
X238420Y642148D03*
X234500Y637685D03*
X229584Y652668D03*
X237451Y652761D03*
X241670Y652558D03*
X233584Y652519D03*
X243596Y671772D03*
X229895Y671672D03*
X239168D03*
X237275Y679609D03*
X240493Y692678D03*
X239084Y696252D03*
X233954Y697395D03*
X236120Y704173D03*
X238348Y712469D03*
X242680Y712337D03*
X234960Y714064D03*
X239210Y720040D03*
X234910Y720816D03*
X243900Y724662D03*
X239440Y736140D03*
X230440Y736412D03*
X234940Y724325D03*
Y733355D03*
X243940Y736412D03*
X239500Y733523D03*
X230440Y724242D03*
X234940Y736392D03*
X236180Y786517D03*
X242230Y774803D03*
X234011Y772902D03*
X240217Y788695D03*
Y791695D03*
X232343D03*
Y788695D03*
X249990Y21219D03*
X245990D03*
X257270Y29334D03*
X258300Y22289D03*
X250290Y45504D03*
X246290D03*
X258103Y53688D03*
X257500Y56117D03*
X245310Y50867D03*
X249300Y50862D03*
X253490Y53736D03*
X253810Y63244D03*
X245600Y66317D03*
X249600D03*
X246073Y92197D03*
X256573Y94097D03*
X247870Y105821D03*
X252683Y105867D03*
X253558Y95038D03*
X256133Y99347D03*
X248558Y95038D03*
X259030Y123727D03*
X259443Y120773D03*
X249453Y114307D03*
X255287Y226709D03*
X254221Y230582D03*
X256492Y222466D03*
X254181Y234521D03*
X257950Y236924D03*
X254418Y240407D03*
X255209Y260639D03*
X255359Y266557D03*
X247389Y259139D03*
X256553Y256881D03*
X249433Y263697D03*
Y260697D03*
X256916Y262609D03*
X247389Y262139D03*
X257253Y259197D03*
X257046Y279607D03*
X255205Y272755D03*
X244109Y277996D03*
X247389Y268139D03*
X257253Y271197D03*
Y268197D03*
X250399Y296848D03*
X253611Y293765D03*
X250399Y290548D03*
X244099Y284248D03*
X250399D03*
X244099Y293698D03*
X258380Y295984D03*
X254334Y298728D03*
X247249Y303148D03*
X244118Y309387D03*
X254007Y306819D03*
X244118Y303187D03*
X257057Y309636D03*
X244099Y299998D03*
X247249Y306298D03*
X257418Y303533D03*
X247281Y315727D03*
X254631Y324716D03*
X254998Y329779D03*
X256276Y322652D03*
X247789Y322910D03*
X254905Y327213D03*
X248509Y339207D03*
X254819Y332435D03*
X250466Y344381D03*
X245691Y341215D03*
X247218Y333049D03*
X255009Y338318D03*
X246685Y337357D03*
X255124Y335244D03*
X247025Y330512D03*
X251334Y352857D03*
X259444Y354291D03*
X246265Y355855D03*
X251491Y357134D03*
X256588Y359005D03*
X244595Y363535D03*
X250661Y384780D03*
X247065Y385398D03*
X244546Y385315D03*
X253762Y385255D03*
X247797Y406029D03*
X250297D03*
X252797D03*
X245297D03*
X244196Y419610D03*
Y417010D03*
X258798Y417594D03*
X254798Y417728D03*
X244196Y427610D03*
Y425010D03*
Y433010D03*
Y435610D03*
X254813Y427018D03*
X252670Y443592D03*
X246465Y464893D03*
X251780Y460883D03*
X257568Y461513D03*
X245609Y517182D03*
X245860Y575049D03*
X249909Y568653D03*
X259678Y581553D03*
X249541Y587156D03*
X253709Y586128D03*
X249541Y583156D03*
X246639Y608378D03*
Y605778D03*
X249640Y602519D03*
X246639Y624378D03*
Y621778D03*
Y616378D03*
Y613778D03*
X249013Y628514D03*
X249462Y648383D03*
X257271Y671772D03*
X252486D03*
X253398Y692357D03*
X244780Y682521D03*
X250795Y703150D03*
X251451Y697465D03*
X259170Y705138D03*
X254940Y712381D03*
X258570Y722981D03*
X255310Y715915D03*
X248530Y721829D03*
X250630Y719457D03*
X253340Y724726D03*
X248440Y736163D03*
X257440Y736041D03*
X252940Y736318D03*
X248770Y724631D03*
X252940Y733567D03*
X256650Y778342D03*
X247900Y778823D03*
X252470Y785797D03*
X252028Y791695D03*
X271421Y7319D03*
X262955Y12663D03*
X273660Y23037D03*
X268579Y19365D03*
X265934Y16522D03*
X273645Y27712D03*
X266111Y29229D03*
X265789Y20990D03*
X268809Y16400D03*
X274990Y16396D03*
X268372Y40782D03*
X265872D03*
X272010Y40553D03*
X274510D03*
X273873Y63167D03*
X269793D03*
X261750Y75886D03*
X267703Y89397D03*
X272245Y89585D03*
X263703Y93847D03*
X271133Y92787D03*
X265830Y102566D03*
X264210Y96914D03*
X273973Y97645D03*
X262473Y106937D03*
X263683Y99902D03*
X269010Y121648D03*
X264980Y121886D03*
X269620Y243240D03*
X269192Y248209D03*
X272242Y244842D03*
X272620Y238653D03*
X260108Y240376D03*
X267118Y245587D03*
X271458Y241347D03*
X270260Y237037D03*
X266187Y249852D03*
X267020Y257079D03*
X263029Y259139D03*
X265073Y266697D03*
X263029Y265139D03*
X271811Y256687D03*
X271898Y263173D03*
X273521Y265849D03*
X260068Y262187D03*
X263268Y262370D03*
X263774Y256464D03*
X272464Y259964D03*
X269263Y252800D03*
X271944Y278363D03*
X264386Y280407D03*
X265944Y278363D03*
X274886Y272587D03*
X273386Y280407D03*
X270444Y270543D03*
X271886Y272587D03*
X265886Y271718D03*
X268886Y272587D03*
X268944Y278363D03*
X263029Y271139D03*
Y268139D03*
X273444Y270543D03*
X274944Y278363D03*
X270386Y280407D03*
X267386D03*
X262886Y288227D03*
X264386Y296047D03*
X267386D03*
X261463Y296111D03*
X265825Y293987D03*
X268867Y293942D03*
X270444Y286183D03*
X265768Y287546D03*
X273444Y286183D03*
X273618Y295387D03*
X271811Y303313D03*
X271944Y309643D03*
X262944D03*
X261386Y311687D03*
X260045Y309615D03*
X268944Y309643D03*
X265944Y309640D03*
X261915Y302033D03*
X269380Y302736D03*
X264501Y303109D03*
X266939Y303281D03*
X274303Y303413D03*
X259820Y303800D03*
X274832Y309687D03*
X262035Y322679D03*
X267883Y325837D03*
X265318Y326487D03*
X270525Y325754D03*
X262201Y328491D03*
X272967Y325842D03*
X275517D03*
X267030Y330147D03*
X262700Y325494D03*
X268502Y344181D03*
X263576Y340898D03*
X274701Y333804D03*
X270326Y335795D03*
X270485Y339030D03*
X264015Y336151D03*
X263173Y331794D03*
X267943Y339617D03*
X270293Y330540D03*
X272964Y330669D03*
X262379Y338103D03*
X262247Y334502D03*
X270071Y333021D03*
X272263Y334222D03*
X272352Y340900D03*
X269456Y355353D03*
X269117Y352876D03*
X269886Y358753D03*
X260536Y374216D03*
X270293Y363972D03*
X267993Y390695D03*
X270796Y386643D03*
X266882Y388165D03*
X261539Y387755D03*
X264421Y384812D03*
X275497Y390758D03*
X263419Y393450D03*
X265162Y401391D03*
X272220Y401343D03*
X262798Y417886D03*
X265532Y422648D03*
X266822Y443297D03*
X275256Y445753D03*
X271035Y443051D03*
X273735Y443034D03*
X263807Y461234D03*
X267741Y491608D03*
X263924Y491754D03*
X269609Y576413D03*
X274309Y574653D03*
X261175Y569054D03*
X263792Y574203D03*
X268009Y570953D03*
X268717Y606015D03*
X261967Y608638D03*
Y605638D03*
X260064Y602993D03*
X261967Y614638D03*
X263467Y626638D03*
X269428Y622966D03*
X261967Y617638D03*
X263467Y623638D03*
X273938Y633084D03*
X273674Y640095D03*
X273548Y636471D03*
X266610Y654171D03*
X270040Y651241D03*
X269640Y655290D03*
X270430Y665576D03*
X269709Y672575D03*
X265913Y671772D03*
X261890Y664761D03*
X265550Y668415D03*
X274360Y673831D03*
X270140Y691038D03*
X267240Y682519D03*
X269420Y677062D03*
X265300Y702131D03*
X269410Y706003D03*
X267124Y707892D03*
X273510Y699749D03*
X266170Y694826D03*
X260680Y712988D03*
X271210Y718000D03*
X264600Y723086D03*
X270940Y722080D03*
X275440Y735626D03*
X261940Y735878D03*
X266440Y736030D03*
X270940Y735642D03*
X263430Y770417D03*
X264340Y778780D03*
X272175Y783074D03*
X271713Y788695D03*
Y791695D03*
X259902D03*
X280699Y13908D03*
X278199D03*
X282180Y10253D03*
X285703Y9813D03*
X278660Y10073D03*
X278305Y23057D03*
X280699Y16408D03*
X278199D03*
X278307Y27707D03*
X284505Y30676D03*
X287766Y21289D03*
X287476Y37125D03*
X277472Y34959D03*
Y37459D03*
X280072Y34330D03*
X275766Y52772D03*
X275800Y50212D03*
X290823Y63167D03*
X282023D03*
X277853D03*
X277000Y88323D03*
X286263Y88677D03*
X276603Y92119D03*
X287423Y91857D03*
X287595Y106109D03*
X279010Y104889D03*
X286710Y95717D03*
X281200Y98369D03*
X289720Y96094D03*
X278760Y101061D03*
X278354Y244281D03*
X290154Y244007D03*
X285934Y243931D03*
X282178Y244005D03*
X279161Y237817D03*
X289254Y255688D03*
X286492Y258364D03*
X283660Y251542D03*
X281954Y255588D03*
X288954Y260788D03*
X276328Y264687D03*
X276904Y252550D03*
X282166Y262922D03*
X281945Y260231D03*
X278811Y259135D03*
X279336Y264795D03*
X277886Y272587D03*
X280886D03*
X286010Y276042D03*
X282867Y281142D03*
X276444Y270543D03*
X282309Y270435D03*
X279444Y270543D03*
X277944Y278363D03*
X279386Y280407D03*
X276386D03*
X281767Y277742D03*
X276507Y295816D03*
X290363Y286082D03*
X286132Y285953D03*
X281818Y290787D03*
X278918Y286887D03*
X276444Y286183D03*
X279386Y311687D03*
X285890Y311357D03*
X277020Y302298D03*
X282337Y308217D03*
X281859Y310862D03*
X277816Y309678D03*
X279754Y303269D03*
X281461Y321744D03*
X280776Y326412D03*
X286071Y329184D03*
X278067Y325842D03*
X282167Y324242D03*
X288466Y325343D03*
X285704Y321809D03*
X275660Y338857D03*
X281212Y338079D03*
X277288Y334282D03*
X282234Y333792D03*
X285794Y339063D03*
X281205Y340997D03*
X279718Y333694D03*
X275602Y343811D03*
X289191Y341348D03*
X290190Y352480D03*
X278943Y346914D03*
X277718Y352687D03*
X282818D03*
X286711Y352668D03*
X283140Y346082D03*
X286020Y356454D03*
X277040Y376172D03*
X279863Y367513D03*
X286550Y374402D03*
X281450Y373151D03*
X276687Y385100D03*
X285390Y390550D03*
X288220Y389630D03*
X283820Y396266D03*
X281142Y402379D03*
X287067Y402358D03*
X280730Y393856D03*
X286210Y444926D03*
X289630Y444828D03*
X283212Y442286D03*
X286100Y442298D03*
X288742Y442090D03*
X287970Y446705D03*
X282000Y444966D03*
X279112Y444954D03*
X276626Y442913D03*
X279990Y442071D03*
X276809Y471853D03*
X276347Y459741D03*
X280210Y460762D03*
X287567Y470649D03*
Y467649D03*
X280380Y467284D03*
X278990Y464793D03*
X284332Y472834D03*
X282298Y483803D03*
X277470Y481197D03*
X280970D03*
X288009Y495653D03*
X284024Y502595D03*
X290323D03*
X287174Y543541D03*
X290323D03*
Y565589D03*
Y559289D03*
Y562439D03*
X277725Y552989D03*
X284024Y556139D03*
X280874D03*
X279658Y574443D03*
X285530Y573002D03*
X291066Y590488D03*
Y593088D03*
X287997Y649064D03*
X280880Y650295D03*
X278699Y656491D03*
X289171Y661908D03*
X289365Y665845D03*
Y673719D03*
X279843Y675688D03*
X288880Y689467D03*
X278350Y687309D03*
X275710Y681593D03*
X289248Y680521D03*
X284760Y707022D03*
X286798Y704143D03*
X278370Y705093D03*
X277475Y695723D03*
X278341Y717269D03*
X289060Y722193D03*
X281830Y722184D03*
X285130Y714433D03*
X275880Y722141D03*
X285880Y722268D03*
X289150Y718548D03*
X279940Y724126D03*
X289240Y724687D03*
X283990Y734977D03*
X280210Y734805D03*
X288390Y734796D03*
X284020Y724956D03*
X284532Y747493D03*
X275627Y777692D03*
X281930Y773190D03*
X286722Y785929D03*
X279587Y791695D03*
X295307Y41260D03*
X295390Y44017D03*
X295610Y50299D03*
X295560Y52907D03*
X294903Y63167D03*
X306693D03*
X303053D03*
X298883D03*
X296093Y88477D03*
X302853Y89057D03*
X301870Y92072D03*
X296870D03*
X294800Y100593D03*
X295490Y97209D03*
X302370Y95215D03*
X291927Y102991D03*
X293505Y94965D03*
X296927Y102991D03*
X303220Y98397D03*
X293873Y130357D03*
X302930Y132994D03*
X300118Y250987D03*
X296176Y249585D03*
X299776Y248010D03*
X295910Y266706D03*
X295110Y262961D03*
X301511Y262204D03*
X300477Y265010D03*
X296210Y253187D03*
X300310Y253842D03*
Y257242D03*
X292710Y266542D03*
X295307Y275439D03*
X294510Y280709D03*
X301473Y282650D03*
X297810Y280709D03*
X301723Y279150D03*
X297782Y291966D03*
X295010Y286767D03*
X301182Y291966D03*
X294382D03*
X305132Y286867D03*
X298332D03*
X301732D03*
X297668Y300709D03*
X294888Y304456D03*
X294781Y309788D03*
X301795Y310398D03*
X296639Y308057D03*
X305250Y310342D03*
X300201Y300874D03*
X303197Y304297D03*
X295200Y321473D03*
X294596Y328129D03*
X297073Y329159D03*
X294218Y343587D03*
X294888Y335326D03*
X298452Y340487D03*
X305880Y339046D03*
X306820Y342146D03*
X299410Y331201D03*
X303759Y331478D03*
X294618Y348287D03*
X293467Y352442D03*
X305446Y359450D03*
X295527Y359812D03*
X298202Y374572D03*
X295388Y375644D03*
X303722Y385367D03*
X293290Y389737D03*
X299533Y394056D03*
X291860Y442927D03*
X292170Y445986D03*
X301240Y470885D03*
X291327Y466811D03*
X300040Y459733D03*
X306220Y477125D03*
X303631Y475607D03*
Y472607D03*
X301209Y488853D03*
X303709Y489353D03*
X297370Y498563D03*
X300209Y495853D03*
X305708Y503043D03*
X296913Y514460D03*
X301457Y513837D03*
X293473Y565589D03*
Y562439D03*
X295047Y554565D03*
X304410Y572782D03*
X291357Y586128D03*
X299121Y597542D03*
X306229Y600263D03*
X301796Y603917D03*
X298303Y613184D03*
X305602Y620685D03*
Y618185D03*
X299629Y623877D03*
X299090Y634421D03*
X293843Y642536D03*
X303110Y639381D03*
X305200Y652883D03*
X301070Y655920D03*
X292850Y656359D03*
X297394Y657033D03*
X302772Y659604D03*
X301360Y652183D03*
X300880Y664296D03*
X294120Y668391D03*
X295890Y662662D03*
X297770Y674720D03*
X292970Y682450D03*
X295950Y689520D03*
X293068Y677108D03*
X296858Y702544D03*
X297300Y697221D03*
X301696Y701851D03*
Y699351D03*
X293286Y703504D03*
X305990Y697189D03*
X303681Y714421D03*
X305213Y720393D03*
X293300Y718944D03*
X296885Y718059D03*
X297223Y715523D03*
X291318Y713875D03*
X291790Y735976D03*
X306540Y724266D03*
X297940Y724377D03*
X302660Y736359D03*
X298160Y736489D03*
X302810Y733807D03*
X298590Y733669D03*
X293480Y725080D03*
X295700Y733133D03*
X293440Y748380D03*
X291340Y771217D03*
X295100Y786269D03*
X299249Y771403D03*
X304740Y777277D03*
X291398Y792234D03*
X299272Y791695D03*
X314640Y63167D03*
X310483D03*
X318543D03*
X322713D03*
X314830Y92851D03*
X312183Y88837D03*
X321463Y88517D03*
X315083Y90207D03*
X311553Y92347D03*
X310850Y99620D03*
X320740Y98599D03*
X312223Y96407D03*
X317970Y95961D03*
X311420Y250230D03*
X311290Y247249D03*
X315410Y258656D03*
X312680Y258353D03*
X307204Y304212D03*
X321643Y321928D03*
X309143D03*
X311643D03*
X314143D03*
X316643D03*
X319143D03*
X322765Y327721D03*
X311740Y325839D03*
X322210Y336696D03*
X319323Y338320D03*
X309510Y344127D03*
X313980Y335813D03*
X314550Y331564D03*
X318480Y335039D03*
X321130Y342418D03*
X309190Y336959D03*
X319666Y354376D03*
X319807Y346376D03*
X321150Y357730D03*
X319288Y350376D03*
X307410Y348380D03*
X309131Y374573D03*
X314860Y367656D03*
X313222Y374229D03*
X322255Y371935D03*
X321297Y367739D03*
X319363Y372149D03*
X315383Y387863D03*
X307116Y385979D03*
X315533Y384749D03*
X310484Y383312D03*
X321144Y399643D03*
X318644D03*
X316190Y413299D03*
X317140Y421775D03*
X321910Y410139D03*
X311610Y432528D03*
X313530Y436460D03*
X315940Y438104D03*
X319478Y429389D03*
X308220Y432552D03*
X322599Y432505D03*
X309440Y426404D03*
X318950Y432473D03*
X316963Y467655D03*
X307800Y467859D03*
X310380Y473942D03*
X316956Y478833D03*
X315980Y472128D03*
X307670Y473605D03*
X320080Y512736D03*
X318968Y536052D03*
X318678Y540966D03*
X321828Y541682D03*
X313888Y566003D03*
X313141Y550821D03*
X313075Y553755D03*
X313108Y556556D03*
X313275Y559590D03*
X316788Y572903D03*
X316688Y569603D03*
X313347Y570695D03*
X319135Y591407D03*
X313419Y594040D03*
X313227Y590232D03*
X310919Y594040D03*
X310627Y590232D03*
X315957Y594127D03*
X312641Y611556D03*
X307996Y611536D03*
X312656Y606881D03*
X307994Y606886D03*
X320094Y604114D03*
X320512Y613603D03*
X308102Y620685D03*
Y618185D03*
X320367Y618071D03*
X314910Y627222D03*
X317722Y614646D03*
X308741Y623871D03*
X311311Y618197D03*
X317492Y618193D03*
X307574Y633762D03*
X310453Y642451D03*
X320360Y642275D03*
X311382Y635432D03*
X314790Y652049D03*
X317130Y653628D03*
X316184Y662630D03*
X314614Y690767D03*
X316184Y687630D03*
X322440Y700130D03*
X320110Y703093D03*
X316165Y693404D03*
X313230Y702465D03*
X317580Y719996D03*
X307113Y713003D03*
X321820Y712680D03*
X311990Y717601D03*
X319620Y716403D03*
X309531Y714298D03*
X312972Y712693D03*
X318090Y712846D03*
X307940Y736445D03*
X311440Y735831D03*
X315940Y735924D03*
X320440Y736031D03*
X307280Y733705D03*
X321930Y724895D03*
X314930Y724533D03*
X307146Y769416D03*
X315020Y780559D03*
X320657Y779595D03*
X320440Y771967D03*
X311083Y791871D03*
X318957Y791695D03*
X336316Y31815D03*
X326353Y63167D03*
X336024Y88176D03*
X329643Y89887D03*
X335668Y92822D03*
X330668D03*
X325360Y92517D03*
X324070Y88861D03*
X336340Y99265D03*
X327950Y101057D03*
X323000Y94337D03*
X325970Y98817D03*
X327430Y108208D03*
X327190Y103818D03*
X337630Y106304D03*
X334720Y102184D03*
X332453Y122297D03*
X323032Y122237D03*
X331583Y128717D03*
X336495Y290569D03*
X331376Y299883D03*
X328526Y308696D03*
X334478Y299604D03*
X336720Y310846D03*
X337293Y316660D03*
X333540Y315590D03*
X332700Y333089D03*
X333726Y353801D03*
X333440Y349221D03*
X327058Y358376D03*
X323040Y354485D03*
X334816Y367787D03*
X337316Y367758D03*
X337330Y372679D03*
X334816Y372609D03*
X336850Y380332D03*
X326282Y399743D03*
X323644Y399643D03*
X325749Y418701D03*
X331090Y424304D03*
X331900Y419317D03*
X336740Y417069D03*
X328290Y424304D03*
X324940Y413899D03*
X336218Y424850D03*
X325180Y432577D03*
X334420Y428660D03*
X336088Y454511D03*
X326190Y448621D03*
X329120Y449203D03*
X327780Y445819D03*
X331360Y447306D03*
X322986Y467109D03*
X325040Y480129D03*
X330115Y490303D03*
X335162Y502791D03*
X326740Y495763D03*
X329672Y502057D03*
X326170Y518386D03*
X335860Y516486D03*
X329348Y533403D03*
X324927Y546013D03*
X328592Y541146D03*
X328352Y545412D03*
X325588Y541447D03*
X332408Y544097D03*
X323154Y556367D03*
Y558867D03*
Y553867D03*
X337550Y558618D03*
Y556118D03*
Y553618D03*
X323088Y561503D03*
X323188Y564503D03*
X330388Y565803D03*
X336057Y575657D03*
X332388Y567703D03*
X328088Y567503D03*
X323931Y589733D03*
X329260Y603381D03*
X328930Y611691D03*
X323346Y621930D03*
X329110Y623514D03*
X330440Y639504D03*
X328032Y642674D03*
X337070Y639759D03*
X326350Y638968D03*
X332710Y642694D03*
X328760Y657144D03*
X335610Y658177D03*
X332747Y655636D03*
X332190Y659883D03*
X329912Y662383D03*
X335915Y675011D03*
X335390Y667895D03*
X326890Y676159D03*
X327257Y672408D03*
X333180Y665611D03*
X335130Y670744D03*
X334313Y663113D03*
X327500Y667244D03*
X324970Y665128D03*
X337030Y677894D03*
X337798Y686721D03*
X324120Y703114D03*
X336110Y693934D03*
X331520Y701642D03*
X332720Y698170D03*
X325841Y719731D03*
X330410Y712895D03*
X325560Y713391D03*
X336990Y735701D03*
X324940Y736067D03*
X329440Y735814D03*
X333940Y735895D03*
X329590Y724283D03*
X334640Y725035D03*
X338270Y733387D03*
X338460Y724585D03*
X326280Y775980D03*
X337800Y774677D03*
X339162Y9304D03*
Y11904D03*
X350411Y21277D03*
X339239Y24232D03*
X339471Y19373D03*
Y16773D03*
X339239Y26832D03*
X346600Y38561D03*
X346150Y36030D03*
X353060Y61504D03*
X349490Y57698D03*
X352578Y74292D03*
X339750Y73383D03*
X350198Y88277D03*
X343111Y88429D03*
X340543Y88647D03*
X345463Y90837D03*
X353713Y93057D03*
X344770Y101718D03*
X351793Y105404D03*
X344873Y94847D03*
X343070Y99372D03*
X340450Y101914D03*
X344073Y124397D03*
X351533Y124697D03*
X343743Y120967D03*
X351373Y134367D03*
X351503Y130972D03*
Y127972D03*
X345297Y284849D03*
X342955Y291523D03*
X341693Y286010D03*
X354170Y308924D03*
X351500Y301795D03*
X340792Y307107D03*
X353903Y314077D03*
X353841Y306194D03*
X339370Y329176D03*
X341910Y325739D03*
X344720D03*
X339600Y332076D03*
X343880Y356989D03*
X349110Y375767D03*
X352420Y375672D03*
X346020Y374075D03*
X343770Y382166D03*
X351650Y420270D03*
X345270Y452745D03*
X346750Y466532D03*
X352890Y479656D03*
X348000Y479150D03*
X352260Y483029D03*
X338762Y479636D03*
X339506Y482841D03*
X348220Y486484D03*
X352160Y502138D03*
X351250Y499752D03*
X348870Y501571D03*
X343420Y497966D03*
X353400Y507260D03*
X353460Y504536D03*
X348190Y511550D03*
X353120Y510003D03*
X350690Y516376D03*
X340902Y503742D03*
X352940Y518025D03*
X341512Y512429D03*
X350902Y512520D03*
X346350Y517286D03*
X340182Y531787D03*
X351110Y531835D03*
X340330Y541931D03*
X341011Y537828D03*
X342190Y565848D03*
X342759Y599193D03*
X339616Y603438D03*
Y605938D03*
X339384Y611544D03*
X339600Y621293D03*
Y618693D03*
X339384Y614144D03*
X353298Y633903D03*
X340340Y638054D03*
X340669Y644827D03*
X348480Y638558D03*
X345580Y638109D03*
X347670Y642285D03*
X351728Y653860D03*
X340630Y655093D03*
X351730Y649206D03*
X339930Y661219D03*
X351730Y663450D03*
X340530Y675658D03*
X351720Y670018D03*
X338970Y670776D03*
X340870Y665042D03*
X340525Y686600D03*
X353260Y688757D03*
X351810Y706800D03*
X339750Y695271D03*
X339010Y700406D03*
X338926Y697752D03*
X344780Y713349D03*
X352400Y722132D03*
X339300Y716800D03*
X342230Y720936D03*
X341190Y712379D03*
X352010Y713968D03*
X342230Y709384D03*
X343730Y724581D03*
X350180Y735880D03*
X350580Y724427D03*
X345610Y733982D03*
X354060Y734790D03*
X350720Y745722D03*
X344710Y785782D03*
X350450Y784982D03*
X346516Y790294D03*
X363025Y12926D03*
X358285Y21325D03*
X366159Y21822D03*
X361930Y60031D03*
X367300Y60442D03*
X356550Y74767D03*
X365670Y64458D03*
X366733Y88477D03*
X359646Y88174D03*
X362133Y90877D03*
X367776Y91746D03*
X358343Y90948D03*
X360827Y108541D03*
X362300Y98674D03*
X369670Y99845D03*
X361470Y101757D03*
X354943Y104191D03*
X354448Y108092D03*
X367560Y120823D03*
X367350Y123927D03*
X365283Y128125D03*
X354580Y298101D03*
X364220Y296795D03*
X357400Y307608D03*
X365970Y299194D03*
X356835Y313894D03*
X369280Y300916D03*
X367220Y303202D03*
X362660Y316986D03*
X357110Y329210D03*
X359410Y317080D03*
X369040Y316735D03*
X369934Y322946D03*
X359120Y331164D03*
X357040Y332970D03*
X365026Y332478D03*
X362540Y361443D03*
X354690Y377000D03*
X364645Y377065D03*
X360960Y389080D03*
X364880Y384455D03*
X364580Y391273D03*
X366140Y407639D03*
X360350Y395873D03*
X369280Y415600D03*
X365850Y414874D03*
X368660Y449478D03*
X369500Y445873D03*
X354565Y451562D03*
X354750Y445325D03*
X369507Y464391D03*
X355150Y486758D03*
X368787Y472998D03*
X368943Y506356D03*
X366426Y527722D03*
Y530222D03*
Y532722D03*
X368238Y522673D03*
X358182Y531231D03*
X357820Y534561D03*
X365329Y546121D03*
X368694Y546159D03*
X368825Y539776D03*
X369918Y592253D03*
X369848Y588903D03*
X363530Y629727D03*
X367858Y657573D03*
X365070Y658065D03*
X365990Y645272D03*
X367870Y650239D03*
X364980Y655266D03*
X363340Y650512D03*
X362173Y665128D03*
X368200Y672132D03*
X368100Y668133D03*
X361810Y675011D03*
X365620Y663069D03*
X365380Y668972D03*
X365160Y672922D03*
X361760Y668716D03*
X367399Y684652D03*
X367866Y677326D03*
X361646Y689228D03*
X367066Y681094D03*
X364320Y680434D03*
X367496Y690248D03*
X364649Y684022D03*
X364765Y687963D03*
X365090Y676923D03*
X364844Y698332D03*
X361786Y699128D03*
X361717Y695128D03*
X367480Y705169D03*
X367614Y693053D03*
X364115Y692990D03*
X367520Y701710D03*
X366510Y723622D03*
X361350Y720720D03*
X361490Y712505D03*
X367350Y713661D03*
X357830Y718682D03*
X363162Y739537D03*
X366430Y731459D03*
X357096Y732976D03*
X360246Y730819D03*
X354520Y728701D03*
X363460Y735388D03*
X364750Y727821D03*
X363359Y743537D03*
X364090Y748565D03*
X354420Y749198D03*
X357610Y748302D03*
X366860Y739956D03*
X354870Y771388D03*
X360160Y775523D03*
X363300Y781303D03*
X367904Y778327D03*
X366201Y787976D03*
X354390Y790294D03*
X366201Y790976D03*
X379940Y17789D03*
X382990Y17519D03*
X371180Y17789D03*
X370960Y20577D03*
X381907Y21507D03*
X383280Y59940D03*
X376006Y60991D03*
X383247Y64141D03*
X373560Y63973D03*
X380906Y88134D03*
X373820Y88400D03*
X372776Y91746D03*
X384450Y108830D03*
X372620Y98355D03*
X384090Y98743D03*
X379160Y102923D03*
X374030Y95000D03*
X382087Y103647D03*
X380483Y99047D03*
X378733Y105987D03*
X384863Y95437D03*
X376100Y108780D03*
X376723Y94178D03*
X377363Y121108D03*
X378183Y124904D03*
X374040Y304980D03*
X373640Y301078D03*
X370460Y305908D03*
X371090Y303487D03*
X384248Y319157D03*
X372080Y330574D03*
X379560Y374955D03*
X379720Y372257D03*
X378830Y386352D03*
X382620Y391882D03*
X379300Y380862D03*
X379286Y378015D03*
X379750Y383965D03*
X382190Y388077D03*
X376600Y408045D03*
X382680Y408202D03*
X374560Y412421D03*
X371260Y412879D03*
X376150Y430405D03*
X383750Y437058D03*
X372320Y439514D03*
X371950Y430527D03*
X378910Y430874D03*
X371080Y448276D03*
X372710Y445705D03*
X375190Y463996D03*
X381239Y467171D03*
X371080Y481589D03*
X374203Y482079D03*
X377284Y473374D03*
X373850Y496585D03*
X381760Y496004D03*
X376540Y498385D03*
X379177Y509798D03*
X383924Y514797D03*
X383617Y517862D03*
X385040Y521754D03*
X384588Y526069D03*
X382632Y530322D03*
Y527822D03*
Y532822D03*
X379733Y549392D03*
X370309Y550322D03*
X377150Y543151D03*
X376490Y540574D03*
X382596Y537379D03*
X382333Y540414D03*
X384485Y552365D03*
X382595Y554166D03*
X383344Y590662D03*
Y593262D03*
X373448Y589053D03*
X373518Y592403D03*
X385573Y629998D03*
X371407Y641507D03*
X373218Y634217D03*
X382580Y637413D03*
X380101Y660239D03*
X379492Y650239D03*
X376089Y646156D03*
X373680Y662417D03*
X376087Y670156D03*
X379461Y675246D03*
X379462Y666156D03*
X376946Y689985D03*
X377681Y694244D03*
X377679Y701168D03*
X377669Y706237D03*
X377100Y697218D03*
X371170Y711574D03*
X382960Y711431D03*
X372110Y720308D03*
X376190Y711259D03*
X375575Y739459D03*
X375548Y731459D03*
X375834Y727459D03*
X377840Y724388D03*
X376770Y734898D03*
X370430Y749138D03*
X373500Y748457D03*
X376960Y788580D03*
Y791580D03*
X399002Y17519D03*
X397655Y21336D03*
X392250Y59899D03*
X389690Y60665D03*
X401310Y61439D03*
X397790Y61360D03*
X393371Y72919D03*
X390355Y75775D03*
X401220Y65155D03*
X399804Y88778D03*
X397442Y90667D03*
X389400Y89232D03*
X392493Y92647D03*
X399653Y108357D03*
X391536Y108990D03*
X398820Y95823D03*
X391190Y104173D03*
X388860Y98010D03*
X400163Y99177D03*
X391310Y99570D03*
X399613Y104657D03*
X391233Y96093D03*
X399150Y131773D03*
X391880Y131692D03*
X398088Y128455D03*
X393088D03*
X399858Y249711D03*
X399298Y257231D03*
X391998Y258251D03*
X399598Y260251D03*
X398258Y252341D03*
X394378Y260501D03*
X392668Y272511D03*
X399608Y275211D03*
X393458Y282931D03*
X392508Y275581D03*
X400928Y293151D03*
X396098Y283931D03*
X398038Y292571D03*
X399880Y319568D03*
X390080Y331575D03*
X389740Y404725D03*
X395740Y407528D03*
X393370Y411618D03*
X399060Y454322D03*
X399050Y450968D03*
X398800Y462248D03*
Y458058D03*
X387080Y486400D03*
X385940Y482478D03*
X388890Y480439D03*
X386410Y477576D03*
X389670Y477262D03*
X389107Y492097D03*
X388982Y496939D03*
X395690Y512774D03*
X396350Y532016D03*
X396558Y522251D03*
X396470Y527847D03*
X396590Y549310D03*
X399590Y553502D03*
X390000Y567345D03*
X396520Y567444D03*
X393596Y567630D03*
X391630Y597900D03*
X391447Y611973D03*
X394389Y604053D03*
X401353Y624007D03*
X399223Y644930D03*
X394380Y643389D03*
X396940Y658078D03*
X396366Y653229D03*
X399363Y653588D03*
X389856Y645705D03*
X396478Y661529D03*
X399911Y661325D03*
X399873Y666411D03*
X400267Y684029D03*
X390000Y689724D03*
X389961Y682218D03*
X396550Y680266D03*
X399829Y690191D03*
X400968Y686699D03*
X390660Y686923D03*
X391910Y696742D03*
X392080Y692796D03*
X391740Y705957D03*
X398620Y701411D03*
X390950Y701922D03*
X389350Y711288D03*
X396150Y708926D03*
X400730Y721954D03*
X394840Y711437D03*
X414949Y75291D03*
X403739Y72783D03*
X404310Y65213D03*
X410713Y76187D03*
X401670Y93807D03*
X404528Y88702D03*
X409060Y92095D03*
X404813Y93887D03*
X407303Y95117D03*
X408072Y109146D03*
X405688Y253581D03*
X404738Y260421D03*
X402948Y253251D03*
X405970Y256489D03*
X405038Y267521D03*
X401728Y277251D03*
X401618Y267351D03*
X403148Y270191D03*
X405248Y272731D03*
X405878Y294071D03*
X403628Y292201D03*
X408790Y317049D03*
X411240Y316482D03*
X403130Y418091D03*
X406200Y417755D03*
X405980Y414630D03*
X405930Y411386D03*
X406140Y424766D03*
X406150Y433203D03*
X406530Y440667D03*
X406000Y444755D03*
X402900Y444842D03*
X406352Y471405D03*
X409054Y483084D03*
X412260Y482881D03*
X410607Y485620D03*
X413607D03*
X413733Y490781D03*
X410733D03*
X407733D03*
Y493781D03*
Y496781D03*
Y499781D03*
X410733Y493781D03*
X413733D03*
X410733Y496781D03*
X413733D03*
X410733Y499781D03*
X413733D03*
X413138Y504813D03*
X413222Y508054D03*
X411439Y516956D03*
X407865Y516627D03*
X405348Y506316D03*
X402458Y505903D03*
X401556Y508937D03*
X409251Y521763D03*
X412088Y521721D03*
X407776Y527426D03*
X405954Y532502D03*
X404336Y545280D03*
X408486Y537333D03*
X416515Y547602D03*
X402499Y554143D03*
X404578Y551838D03*
X408736Y551529D03*
X413342Y556219D03*
X410522Y593947D03*
X413022D03*
X406884Y594176D03*
X406881Y591322D03*
X412783Y605500D03*
X416454Y621319D03*
X413105Y613739D03*
X403904Y618333D03*
X410085Y618329D03*
X413930Y639810D03*
X403970Y642364D03*
X406100Y631851D03*
X410989Y652957D03*
X413535Y646804D03*
X411982Y660285D03*
X413718Y655267D03*
X413966Y675624D03*
X415218Y664203D03*
X411675Y672654D03*
X411065Y667516D03*
X414183Y686151D03*
X411862Y688027D03*
X413643Y680004D03*
X411149Y678387D03*
X415834Y693272D03*
X412878Y693183D03*
X414550Y707464D03*
X414318Y700979D03*
X414810Y696968D03*
X409581Y711643D03*
X402540Y710649D03*
X412080Y719034D03*
X414080Y721334D03*
X415730Y710897D03*
X406720Y723395D03*
X413940Y735665D03*
X409010Y726147D03*
X415780Y747078D03*
X421893Y123537D03*
X421473Y160556D03*
Y157556D03*
X421640Y228403D03*
Y223403D03*
X422698Y244301D03*
X422288Y250661D03*
X419038Y242611D03*
X428405Y245194D03*
X424961Y241203D03*
X418905Y245694D03*
X426992Y250016D03*
X427768Y253569D03*
X422178Y266891D03*
X428208Y262109D03*
X422528Y253531D03*
X426335Y267062D03*
X418575Y263691D03*
X420858Y261331D03*
X427817Y258829D03*
X418597Y273538D03*
X418698Y279631D03*
X426948Y281051D03*
X421728Y279141D03*
X428748Y275222D03*
X418998Y289871D03*
X422918Y289501D03*
X418588Y286681D03*
X421128Y292601D03*
X423178Y284601D03*
X427909Y286759D03*
X427468Y292287D03*
X418718Y301181D03*
X428747Y463314D03*
Y468770D03*
X419071Y509283D03*
X431280Y514223D03*
X431356Y516836D03*
X422050Y517028D03*
X425999Y516211D03*
X424873Y513921D03*
X423278Y525160D03*
X428874Y525193D03*
X417520Y525128D03*
X428874Y530627D03*
X417520Y531177D03*
X428745Y536999D03*
X423332Y536763D03*
X417617Y536773D03*
X426068Y546048D03*
X417979Y545352D03*
X428039Y548119D03*
X421461Y547703D03*
X420883Y556729D03*
X428039Y556539D03*
X423861Y556535D03*
X431145Y556608D03*
X429340Y596874D03*
X422210Y605343D03*
X431520Y607039D03*
X422221Y619873D03*
X422470Y647852D03*
X432180Y647458D03*
X425334Y656419D03*
X429820Y656709D03*
X425146Y672426D03*
X430140Y665660D03*
X417974Y663446D03*
X421080Y665945D03*
X422510Y677836D03*
X430873Y684536D03*
X425173Y688588D03*
X422981Y690351D03*
X427210Y691934D03*
X423317Y705344D03*
X423055Y696713D03*
X427230Y707377D03*
X426391Y701173D03*
X423242Y707949D03*
X425590Y695895D03*
X421350Y694003D03*
X422940Y723802D03*
X427130Y717871D03*
X421730Y717398D03*
X429240Y721014D03*
X424410Y718429D03*
X417330Y717420D03*
X431440Y723955D03*
X420160Y724309D03*
X430940Y735895D03*
X426430Y735126D03*
X418440Y735930D03*
X420290Y733741D03*
X423900Y736055D03*
X424200Y733399D03*
X426440Y724240D03*
X421690Y779548D03*
X417880Y786361D03*
X428250Y772054D03*
X426900Y779752D03*
X421321Y791476D03*
X417384D03*
X446268Y69074D03*
X442380Y75513D03*
X439670Y70044D03*
X446088Y90159D03*
Y85159D03*
Y87659D03*
X446920Y78358D03*
X447715Y97926D03*
X434158Y122272D03*
X443448Y124552D03*
X441518Y122242D03*
X434158Y125092D03*
X444828Y122132D03*
X446522Y146932D03*
X433253Y160737D03*
X433363Y157607D03*
X444550Y184057D03*
X442520Y223623D03*
X442580Y236459D03*
X441580Y250730D03*
X443212Y240957D03*
X447900Y265292D03*
X441498Y266731D03*
X441792Y259473D03*
X442148Y279361D03*
X442165Y271284D03*
X441076Y294906D03*
X445540Y288853D03*
X445890Y283317D03*
X441361Y300812D03*
X438340Y403375D03*
X439150Y400930D03*
X443240Y401984D03*
X446830Y400551D03*
X445900Y403460D03*
X437887Y471073D03*
X444920Y485259D03*
X447770Y485290D03*
X437716Y476295D03*
X445366Y490657D03*
X445199Y494590D03*
X439749Y506523D03*
X439762Y515540D03*
Y523757D03*
X447781Y523888D03*
X434605Y521488D03*
X442763Y549595D03*
X445838Y538085D03*
X435998Y539726D03*
X434203Y542897D03*
X438722Y538842D03*
X441063Y540563D03*
X448329Y534995D03*
X441326Y556050D03*
X437832Y556374D03*
X434187Y556444D03*
X442240Y553337D03*
X437516Y587579D03*
X441230Y587341D03*
X447830Y588739D03*
X446378Y582681D03*
X435319Y600123D03*
X440040Y608537D03*
X437120Y612933D03*
X440135Y615808D03*
X448460Y625960D03*
X445604Y629045D03*
X433872Y645119D03*
X446980Y638774D03*
X437100Y643793D03*
X446500Y645075D03*
X443850Y634754D03*
X439250Y630973D03*
X434681Y642639D03*
X435420Y647117D03*
X437509Y648996D03*
X446799Y657526D03*
X444700Y651900D03*
X445270Y660832D03*
X444403Y665963D03*
X447210Y665143D03*
X447161Y673564D03*
X444458Y669350D03*
X440688Y684438D03*
Y689438D03*
X440690Y702386D03*
X440688Y694438D03*
X446900Y714648D03*
X442650Y719485D03*
X446260Y722014D03*
X444530Y723917D03*
X440660Y712065D03*
X439200Y722093D03*
X447240Y724780D03*
X439940Y735507D03*
X443940Y735681D03*
X435440Y735928D03*
X436440Y724710D03*
X442120Y724781D03*
X447680Y733564D03*
X444370Y770152D03*
X434540Y778500D03*
X441006Y785297D03*
Y791476D03*
X437069D03*
X458120Y44721D03*
X464170Y56436D03*
X450618Y69004D03*
X457583Y66384D03*
X454263Y77675D03*
X458598Y77967D03*
X462294Y87759D03*
Y85259D03*
Y90259D03*
X461516Y78275D03*
X450917Y97566D03*
X461594Y99342D03*
X449538Y105144D03*
X453168D03*
X453940Y98586D03*
X460412Y105704D03*
X457912D03*
X462912D03*
X453298Y122254D03*
X450798D03*
X452158Y124582D03*
X458818Y122065D03*
Y125422D03*
X461880Y150596D03*
X455292Y162797D03*
X455470Y166963D03*
X452669Y157140D03*
X455913Y178698D03*
X462790Y183489D03*
X452115Y195057D03*
X450650Y203785D03*
X450576Y234431D03*
X454150Y249053D03*
X453620Y245162D03*
X459990Y245930D03*
X457165Y262368D03*
X456800Y259233D03*
X459108Y253181D03*
X449860Y267121D03*
X456530Y256034D03*
X449290Y276227D03*
X449860Y272121D03*
X452900Y281647D03*
X453780Y292411D03*
X453810Y289325D03*
X451790Y300129D03*
X461130Y408318D03*
X448970Y403846D03*
X451950Y402434D03*
X461080Y411451D03*
X463690Y451813D03*
X461590Y446700D03*
X461540Y449833D03*
X457702Y475480D03*
X460702D03*
X454702D03*
X463702D03*
X450899Y483452D03*
X463540Y495717D03*
X457537Y495546D03*
X454770Y495587D03*
X450813Y492993D03*
X452895Y510061D03*
X449402Y515514D03*
X451504Y529734D03*
X450540Y521331D03*
X463991Y531504D03*
X451325Y525981D03*
X456722Y529536D03*
X454022Y541052D03*
X463031Y543563D03*
X453917Y550069D03*
X450367Y540720D03*
X453700Y545047D03*
X453854Y555069D03*
X460236Y581679D03*
X450778Y583106D03*
X458600Y599200D03*
X453775Y600614D03*
X462270Y612911D03*
X453935Y624739D03*
X459690Y626423D03*
X464050Y633877D03*
X458903Y644884D03*
X456342Y649436D03*
X461997Y654507D03*
X463178Y647483D03*
X458650Y666543D03*
X460587Y669424D03*
X457138Y663251D03*
X463020Y661023D03*
X464330Y663251D03*
X458820Y674137D03*
X463120Y681992D03*
X460530Y681874D03*
X459650Y685993D03*
X457730Y682010D03*
X456960Y685581D03*
X461960Y684394D03*
X459950Y722720D03*
X453960Y723142D03*
X449060Y721761D03*
X457060Y722427D03*
X460822Y712620D03*
X451820Y712210D03*
X454070Y714226D03*
X453530Y736212D03*
X458050Y725053D03*
X462440Y735687D03*
X455410Y734113D03*
X450410Y733682D03*
X451320Y725044D03*
X461565Y785806D03*
X463750Y780452D03*
X454120Y785923D03*
X460691Y791476D03*
X456754D03*
X475310Y59746D03*
X464767Y78145D03*
X475030Y63879D03*
X479450Y63721D03*
X466647Y91224D03*
X466682Y102410D03*
X474381Y125310D03*
X478088Y125219D03*
X473200Y140300D03*
X468400Y135800D03*
X470324Y133424D03*
X474813Y162220D03*
X467473Y159766D03*
X473951Y157235D03*
X473950Y172124D03*
X475760Y168747D03*
X472670Y166398D03*
X473580Y177859D03*
X474630Y174843D03*
X480220Y185766D03*
X475770Y186451D03*
X468452Y197934D03*
X471300Y201900D03*
X476400Y203100D03*
X466200Y207300D03*
X471795Y267941D03*
X464810Y311253D03*
X470090Y332824D03*
X475190Y339013D03*
X474140Y408318D03*
X469590D03*
X465330D03*
X468210Y401505D03*
X465913Y402659D03*
X465883Y399834D03*
X474080Y411451D03*
X469530D03*
X465270D03*
X480050Y419556D03*
X471540Y437214D03*
X473140Y439971D03*
X469500Y447730D03*
X467920Y451667D03*
X472210Y450267D03*
X465730Y449833D03*
X465790Y446700D03*
X479575Y467597D03*
X479754Y462988D03*
X466702Y475480D03*
X480118Y479107D03*
Y474107D03*
X466307Y495676D03*
X474130Y553659D03*
X474290Y563565D03*
X471804Y561085D03*
Y556085D03*
X468740Y585897D03*
X469890Y596580D03*
X473294Y613207D03*
X473153Y622451D03*
X476320Y629280D03*
X465580Y641417D03*
X469229Y638135D03*
X475820Y635422D03*
X478905Y659426D03*
X470190Y648693D03*
X468810Y652180D03*
X479512Y649436D03*
X468540Y655799D03*
X479353Y668666D03*
X466049Y675327D03*
X466980Y667059D03*
X469977Y676496D03*
X468260Y664366D03*
X469467Y679915D03*
X479354Y677054D03*
X477710Y722299D03*
X466620Y714137D03*
X473940Y714184D03*
X471450Y736368D03*
X466440Y735987D03*
X471310Y733811D03*
X466440Y724465D03*
X470550Y724034D03*
X473560Y724951D03*
X465850Y733428D03*
X476980Y736594D03*
X476160Y734205D03*
X474940Y747192D03*
X471780Y786300D03*
X476439Y791476D03*
X486810Y60785D03*
X483240Y60546D03*
X487030Y68075D03*
X488438Y109623D03*
Y100123D03*
X484068Y99980D03*
X494355Y108674D03*
X491875Y125222D03*
X487140Y123397D03*
X484350Y112811D03*
X487020Y119754D03*
X494910Y133316D03*
X487857Y152147D03*
X490760Y154771D03*
X488570Y147486D03*
X492424Y142234D03*
X494467Y148867D03*
X488220Y157515D03*
X490130Y163086D03*
X493670Y171871D03*
X489040Y169483D03*
X482500Y184169D03*
X487080Y180918D03*
X482980Y181071D03*
X488850Y175419D03*
X494210Y175035D03*
X495300Y201600D03*
X487839Y194142D03*
X488017Y203716D03*
X486370Y189279D03*
X491046Y207506D03*
X486738Y210434D03*
X487168Y214568D03*
X492700Y223800D03*
X488816Y242877D03*
X484169Y272867D03*
X484780Y314090D03*
X494850Y315733D03*
X480830Y333921D03*
X495140Y385762D03*
X486300Y422150D03*
X481300D03*
X486670Y426196D03*
X495500Y447465D03*
X482880Y467935D03*
Y462935D03*
X483685Y473522D03*
X483641Y479628D03*
X492260Y482826D03*
X494980Y482979D03*
X490334Y497342D03*
X486640Y543687D03*
X483209Y545250D03*
Y550250D03*
X490661Y547148D03*
X489962Y540849D03*
X489938Y563425D03*
X486720Y563730D03*
X481380Y553210D03*
X483838Y566194D03*
Y556148D03*
Y561148D03*
X490658Y579025D03*
X487398Y576665D03*
X490693Y570770D03*
X490538Y567825D03*
X481410Y573563D03*
X483838Y571194D03*
X485890Y590563D03*
X489380Y590839D03*
X485380Y596505D03*
X485738Y587125D03*
X490738D03*
X481340Y593296D03*
X494238Y600441D03*
X490600Y608136D03*
X489800Y600200D03*
X487832Y624429D03*
X490040Y622140D03*
X491100Y644351D03*
X480310Y642224D03*
X491930Y654203D03*
X495622Y660178D03*
X481253Y654837D03*
X493020Y646701D03*
X484700Y660355D03*
X491157Y675604D03*
X482398Y673087D03*
X482544Y668042D03*
X490120Y662703D03*
X492770Y665090D03*
X491189Y679656D03*
X494323Y687669D03*
X481227Y685366D03*
Y691366D03*
X494340Y691623D03*
X490900Y706145D03*
X481227Y696366D03*
X495560Y694781D03*
X488180Y719244D03*
X490890Y714898D03*
X488090Y710545D03*
X496000Y736152D03*
X483180Y736506D03*
X487940Y735681D03*
X491890Y735740D03*
X494850Y733252D03*
X480620Y734244D03*
X480770Y778125D03*
X485870Y776087D03*
X491720Y776713D03*
X495110Y771733D03*
X480376Y791476D03*
X502900Y57670D03*
X496955Y99958D03*
X508955Y99978D03*
X500955Y100139D03*
X504955Y99830D03*
X500310Y109211D03*
X508904Y124063D03*
X497430Y124024D03*
X504750Y111749D03*
X509691Y112938D03*
X499456Y128666D03*
X509710Y127269D03*
X500215Y136449D03*
X502132Y146686D03*
X496360Y167221D03*
X501040Y177297D03*
X498940Y179744D03*
X510000Y173500D03*
X502999Y180541D03*
X499154Y194198D03*
X509100Y191900D03*
X505580Y192555D03*
X498875Y217172D03*
X506234Y207368D03*
X499075Y235575D03*
X496123Y233500D03*
X504941Y227859D03*
X498867Y227773D03*
X504160Y255584D03*
X511070Y310719D03*
X509140Y338005D03*
X504897Y390481D03*
X497111Y388567D03*
X502111D03*
X505819Y417473D03*
X510577Y417741D03*
X498238Y417825D03*
X502687Y417453D03*
X499551Y429636D03*
X502494Y436725D03*
X509486Y433829D03*
X497818Y440265D03*
X509464Y450265D03*
X506456Y446928D03*
X505442Y458719D03*
X502938Y463823D03*
X505843Y465018D03*
X498119Y470011D03*
X511070Y493380D03*
X511520Y496255D03*
X505740Y495880D03*
X511230Y499059D03*
X506230D03*
X511560Y513792D03*
X504613Y522050D03*
Y525200D03*
X501331Y528932D03*
X500138Y543225D03*
X503448Y540235D03*
X505718Y542865D03*
X503338Y549825D03*
Y544825D03*
X500038Y555925D03*
Y550725D03*
X500138Y563025D03*
Y558625D03*
X500338Y566425D03*
X510338Y571325D03*
X500438Y574925D03*
X500419Y578644D03*
X500538Y572025D03*
X500338Y569425D03*
X499868Y585725D03*
X500538Y588525D03*
X505738Y590525D03*
Y600425D03*
X496140Y608883D03*
X504268Y608625D03*
X508024Y613598D03*
X500538Y600925D03*
X504980Y616425D03*
X508400Y617803D03*
X502080Y622999D03*
X498350Y627580D03*
X505780Y642543D03*
X501120Y633249D03*
X510700Y634300D03*
X496690Y633589D03*
X501940Y644073D03*
X498666Y653012D03*
X505690Y654419D03*
X508061Y645381D03*
X504295Y649612D03*
X504114Y670830D03*
X496453Y670876D03*
X501914Y675624D03*
X504241Y665809D03*
X497320Y665216D03*
X506470Y683512D03*
X496577Y684553D03*
X505580Y679105D03*
X496277Y678185D03*
X501540Y681970D03*
X506409Y691373D03*
X497350Y699767D03*
X506092Y697575D03*
X510608Y717448D03*
X502890Y736349D03*
X506105Y724132D03*
X498080Y733252D03*
X509855Y724107D03*
X500260Y729094D03*
X501604Y733003D03*
X501890Y746663D03*
X507935Y785704D03*
X511770Y779940D03*
X499270Y776431D03*
X504440Y772548D03*
X500061Y791476D03*
X496124D03*
X513120Y72069D03*
X512955Y100428D03*
X524955Y99359D03*
X516955Y100333D03*
X520955Y100444D03*
X512878Y108635D03*
X519625Y108543D03*
X526835Y108314D03*
X525570Y124623D03*
X516146Y113121D03*
X522111Y113310D03*
X518248Y137692D03*
X518640Y125539D03*
X518477Y141401D03*
X527349Y152246D03*
X526875Y161838D03*
X512600Y178900D03*
X515600Y172800D03*
X521320Y178184D03*
X516100Y178100D03*
X526621Y177079D03*
X512200Y204200D03*
X526443Y194116D03*
X514500Y194300D03*
X525293Y191705D03*
X515231Y191334D03*
X520015Y194584D03*
X523593Y198171D03*
X512200Y196000D03*
X511997Y207730D03*
X520068Y207142D03*
X516551Y214987D03*
X526657Y207363D03*
X524405Y212531D03*
X514766Y208222D03*
X519183Y224173D03*
X519300Y220500D03*
X516625Y230075D03*
X517670Y247527D03*
X515675Y254098D03*
X525480Y268959D03*
X518590Y310129D03*
X526250Y310940D03*
X519650Y320384D03*
X522420Y315475D03*
X517260Y315978D03*
X523930Y321642D03*
X514400Y340829D03*
X520510Y337299D03*
X527438Y340353D03*
X517617Y422944D03*
X514820Y417617D03*
X526440Y422428D03*
X527300Y417368D03*
X526440Y432077D03*
X515780Y434039D03*
X517929Y439676D03*
X523667Y438452D03*
X522379Y431974D03*
X513140Y452621D03*
X519440Y452321D03*
X526340D03*
X512867Y443679D03*
X516353Y443517D03*
X523838Y442723D03*
X513140Y459721D03*
Y466021D03*
X525640Y473021D03*
X519640D03*
X513140D03*
X516353Y480708D03*
X525603Y480187D03*
X525638Y484023D03*
X519490Y496645D03*
X525698Y496724D03*
X519938Y493125D03*
X524938D03*
X522250Y513692D03*
X514430Y511801D03*
X519430D03*
X527138Y529525D03*
X523938Y528725D03*
X515110Y528785D03*
X519438Y543025D03*
X513480Y541499D03*
X518938Y540425D03*
X521938Y540325D03*
X516380Y540364D03*
X525338Y540125D03*
X513838Y556925D03*
X516738Y562425D03*
X513738D03*
X512354Y590825D03*
X524638Y590225D03*
X520228Y590335D03*
X519638Y600425D03*
X523538Y600325D03*
X527438D03*
X514058Y605055D03*
X523800Y611145D03*
X520370Y625158D03*
X526300Y623621D03*
X518920Y615387D03*
X519830Y634663D03*
X514320Y641085D03*
X515371Y658880D03*
X515438Y649996D03*
X525692Y654862D03*
X517328Y655529D03*
X521516Y650576D03*
X517806Y670102D03*
X517222Y673917D03*
X518800Y665776D03*
X515541Y661845D03*
X526430Y664730D03*
X515425Y685783D03*
X518382Y678247D03*
X515429Y692278D03*
X526600Y679117D03*
X517888Y687901D03*
X518947Y685122D03*
X527111Y686052D03*
X515429Y697278D03*
X518500Y723073D03*
X512548Y722093D03*
X514620Y713193D03*
X517443Y717011D03*
X517775Y711203D03*
X522865Y711178D03*
X514498Y716473D03*
X519440Y735681D03*
X512140Y736554D03*
X514901Y724120D03*
X523370Y724131D03*
X516940Y735683D03*
X521800Y732667D03*
X514420Y733131D03*
X524576Y733227D03*
X512610Y747115D03*
X525110Y774395D03*
X519440Y772861D03*
X519746Y791476D03*
X515809D03*
X539510Y108742D03*
X542248Y106333D03*
X536955Y100257D03*
X532955Y108669D03*
X528955Y99781D03*
X532955Y100604D03*
X535960Y112850D03*
X527613Y113373D03*
X542700Y112881D03*
X527898Y147146D03*
X538655Y151415D03*
X538294Y159415D03*
X533483Y177449D03*
X533797Y180764D03*
X539500Y196500D03*
X536232Y192086D03*
X529592Y192999D03*
X533474Y196500D03*
X541657Y207645D03*
X532320Y209470D03*
X532500Y206500D03*
X536676Y234993D03*
X534208Y227832D03*
X528105Y230594D03*
X536576Y246993D03*
X539438Y250323D03*
X535772Y250076D03*
X529527Y265584D03*
X539267Y267102D03*
X532794Y282068D03*
X530119Y280101D03*
X528680Y317349D03*
X541380Y340358D03*
X543110Y333848D03*
X536180Y341432D03*
X536170Y336603D03*
X531795Y340409D03*
X531430Y337074D03*
X527603Y337208D03*
X529910Y419478D03*
X540700Y418852D03*
X541650Y422280D03*
X536440Y421973D03*
X530940Y422207D03*
X541440Y431787D03*
X536440Y431923D03*
X531440Y432178D03*
X529968Y440216D03*
X529028Y430469D03*
X535352Y440414D03*
X542738Y455823D03*
X530038Y444323D03*
X533040Y453221D03*
X540141Y442994D03*
X534738Y445523D03*
X541838Y450723D03*
X533740Y458021D03*
Y465021D03*
X542738Y463123D03*
X533740Y473021D03*
X540938Y473623D03*
X535729Y476632D03*
X539419Y491107D03*
X532934Y491384D03*
X538038Y488323D03*
X533038D03*
X543280Y491040D03*
X530438Y529525D03*
X541538Y529625D03*
X534401Y529562D03*
X530638Y539525D03*
X534638Y539825D03*
X541238Y539625D03*
X528138Y539925D03*
X533038Y590325D03*
X535776Y590487D03*
X530338Y590325D03*
X536438Y600425D03*
X542438Y613723D03*
X529408Y603485D03*
X540540Y601008D03*
X538828Y602945D03*
X542848Y602975D03*
X535048Y602885D03*
X538400Y613804D03*
X527828Y615387D03*
X532420Y615484D03*
X540048Y629641D03*
X530779Y637354D03*
X532479Y633588D03*
X535230Y648711D03*
X542424Y654821D03*
X536557Y655498D03*
X529525Y669349D03*
X529899Y661020D03*
X539734Y675020D03*
X539830Y667332D03*
X531599Y689838D03*
X533270Y679351D03*
X531597Y697509D03*
X535485Y715182D03*
X535272Y711217D03*
X535062Y708679D03*
X530012Y708618D03*
X539577Y721891D03*
X537503Y710088D03*
X528388Y722903D03*
X540062Y708779D03*
X537702Y735662D03*
X541940Y735681D03*
X528440D03*
X531845Y724095D03*
X532940Y734810D03*
X531029Y733142D03*
X539650Y780942D03*
X529300Y771341D03*
X533600Y778780D03*
X539431Y791476D03*
X535494D03*
X547248Y106582D03*
X555938Y97292D03*
X551454Y97154D03*
X557995Y110244D03*
X546306Y110193D03*
X550490Y112989D03*
X548367Y135415D03*
X548007Y139415D03*
X552173Y138528D03*
X550599Y132596D03*
X547543Y143415D03*
X550550Y151682D03*
X558059Y154254D03*
X558348Y142511D03*
X551464Y143862D03*
X550604Y168072D03*
X558845Y158697D03*
X550370Y157461D03*
X557668Y176534D03*
X555510Y173872D03*
X551395Y174172D03*
X558768Y191223D03*
X544500Y197500D03*
X546000Y192000D03*
X553909Y207401D03*
X547927Y212190D03*
X558416Y210682D03*
X544700Y216100D03*
X544500Y207000D03*
X547148Y220220D03*
X545424Y226722D03*
X546690Y233066D03*
X544990Y231086D03*
X549488Y233003D03*
X549358Y230153D03*
X552120Y232388D03*
X552050Y229124D03*
X545703Y245725D03*
X545981Y236287D03*
X550090Y247079D03*
X545116Y266847D03*
X547929Y258102D03*
X545223Y276895D03*
X557207Y280328D03*
X555072Y289563D03*
X557222Y285109D03*
X553690Y340829D03*
X547340Y339103D03*
X555707Y389146D03*
X552090Y388953D03*
X548470Y378127D03*
X544500Y422583D03*
X557017Y438968D03*
X549574Y432582D03*
X543381Y448428D03*
X556771Y456156D03*
X556959Y443009D03*
X551140Y445789D03*
X555140Y445940D03*
X546384Y445107D03*
X547488Y452373D03*
X556971Y460656D03*
X554550Y469674D03*
X545513Y469740D03*
X543338Y459323D03*
X547638Y462356D03*
X546038Y457523D03*
X547340Y484025D03*
X546250Y490302D03*
X548000Y509493D03*
X547880Y515743D03*
X544370Y510267D03*
Y515267D03*
X544138Y530125D03*
X554860Y531701D03*
X549920Y527242D03*
X545413Y547950D03*
X551538Y540325D03*
X551338Y544225D03*
X551438Y561225D03*
Y563825D03*
X551538Y568525D03*
X550938Y587325D03*
X551238Y584025D03*
X543850Y590313D03*
X548138Y600425D03*
X544638Y600525D03*
X553619Y601204D03*
X550149Y604639D03*
X546938Y613828D03*
X543400Y625963D03*
X552350Y614028D03*
X552849Y631652D03*
X558281Y637840D03*
X551030Y637200D03*
X543400Y635615D03*
X545377Y647594D03*
X549314D03*
X551230Y652844D03*
X551283Y670800D03*
X547346Y697581D03*
X544984Y699419D03*
X551283Y699243D03*
X544934Y720820D03*
X550535Y721903D03*
X555551Y722342D03*
X557488Y713709D03*
X553725Y717251D03*
X550004Y709559D03*
X555062Y708679D03*
X545062D03*
X555148Y735583D03*
X550940Y735681D03*
X546440D03*
X553193Y724847D03*
X546566Y724119D03*
X544082Y724460D03*
X549049Y724412D03*
X557426Y724436D03*
X557978Y734053D03*
X545300Y783152D03*
X550940Y771858D03*
X554870Y779438D03*
X555179Y791476D03*
X566090Y109136D03*
X560938Y97195D03*
X569559Y103123D03*
X563230Y150222D03*
X564076Y145372D03*
X563410Y165289D03*
X563274Y162169D03*
X562195Y159015D03*
X563129Y178369D03*
X559646Y174476D03*
X561909Y207393D03*
X572690Y226569D03*
X572020Y222393D03*
X567980Y222353D03*
X568410Y226647D03*
X561258Y230153D03*
X566248Y230283D03*
X563506Y232027D03*
X571576Y246693D03*
X564676D03*
X571476Y260093D03*
X564676D03*
Y253693D03*
X564274Y279395D03*
X566774Y275195D03*
X566876Y289890D03*
X561525Y298192D03*
X560865Y285434D03*
X565953Y301635D03*
X567320Y415088D03*
X565310Y412700D03*
X565977Y456156D03*
X566059Y460956D03*
X572440Y464323D03*
Y469323D03*
X562340Y484252D03*
X561610Y503885D03*
X560960Y510151D03*
X571830Y509411D03*
X573840Y512108D03*
X564370Y504117D03*
Y509117D03*
X567791Y528325D03*
X568068Y525306D03*
X561065Y543998D03*
X560838Y540325D03*
X562308Y536895D03*
X566298Y548465D03*
X563188Y541925D03*
X566338Y554235D03*
X561174Y564471D03*
X574738Y579525D03*
X565858Y576195D03*
X561198Y581793D03*
X566378Y567725D03*
X561608Y571775D03*
X574537Y591325D03*
X574738Y587425D03*
X574645Y583525D03*
X565398Y584765D03*
X568163Y595115D03*
X561568Y589355D03*
X574071Y606204D03*
X568930Y607754D03*
X571650Y625998D03*
X574730Y625521D03*
X565647Y637705D03*
X565556Y632431D03*
X571790Y646799D03*
X559440Y650767D03*
X566950Y659439D03*
X563850Y659575D03*
X563840Y653515D03*
X565168Y664614D03*
Y674614D03*
Y669614D03*
Y684614D03*
X563586Y682137D03*
X563577Y692284D03*
X563441Y676872D03*
X565168Y679614D03*
X563393Y686908D03*
X565168Y689614D03*
X568215Y702343D03*
X565168Y694614D03*
Y699614D03*
X568288Y715547D03*
X560544Y718091D03*
X569604Y721248D03*
X574190Y717805D03*
X564319Y721587D03*
X562540Y713454D03*
X560062Y708679D03*
X570614Y713237D03*
X565062Y708679D03*
X568908Y735883D03*
X573440Y735681D03*
X564438Y735853D03*
X560350Y735807D03*
X573440Y724053D03*
X568940Y724090D03*
X562395Y724557D03*
X571232Y732545D03*
X566798Y734023D03*
X569680Y771106D03*
X560150Y781347D03*
X562700Y772391D03*
X572720Y777184D03*
X559116Y791476D03*
X578938Y103123D03*
X583829Y117732D03*
X583661Y121836D03*
X580501Y138336D03*
X583829Y132232D03*
X583547Y128232D03*
X581565Y154969D03*
X583970Y144589D03*
X580180Y148894D03*
X579540Y143304D03*
X579897Y161355D03*
X584438Y160933D03*
X582792Y167632D03*
X581915Y179955D03*
X582920Y194220D03*
X588692Y192809D03*
X585580Y210516D03*
X579707Y220662D03*
Y229395D03*
X585579Y230095D03*
X576105Y231626D03*
X578076Y246693D03*
Y253393D03*
Y260093D03*
X575874Y282395D03*
X581474Y274795D03*
X575874Y289895D03*
Y285995D03*
X575880Y293016D03*
X575908Y295606D03*
X583853Y313783D03*
X585584Y308881D03*
X579168Y313641D03*
X588607Y305034D03*
X576650Y311446D03*
X581650D03*
X583737Y321204D03*
X585984Y323246D03*
X579788Y354743D03*
X589070Y423525D03*
X578830Y448192D03*
X575550Y463784D03*
X575650Y469996D03*
X588153Y459599D03*
X579600Y508878D03*
X578840Y512108D03*
X585013Y547959D03*
X575438Y545425D03*
X589036Y548825D03*
X583890Y537093D03*
X576208Y542405D03*
X575838Y548935D03*
X575238Y552025D03*
X575038Y554725D03*
X575138Y559825D03*
X577778Y556355D03*
X575038Y567725D03*
X575538Y571725D03*
X574876Y575625D03*
X586369Y585801D03*
X588780Y611056D03*
X586810Y603344D03*
X579500Y625963D03*
X577000Y620029D03*
X588780Y616056D03*
X587440Y656958D03*
X576700Y655594D03*
X588950Y650070D03*
X583930Y652439D03*
X577217Y652002D03*
X576987Y660180D03*
X580740Y653286D03*
X584903Y663828D03*
X580637Y663629D03*
X576846Y675985D03*
X579076Y669603D03*
X576520Y667750D03*
X586060Y682582D03*
X587040Y688218D03*
X589050Y680160D03*
X579980Y683140D03*
X576644Y679562D03*
X578030Y690236D03*
X577010Y682718D03*
X576519Y687665D03*
X589500Y690546D03*
X586995Y694080D03*
X576442Y705492D03*
X585400Y697289D03*
X584312Y710716D03*
X579220Y720776D03*
X585693Y722428D03*
X583440Y735856D03*
X587940Y735681D03*
X587963Y724108D03*
X577940Y724127D03*
X583440Y724927D03*
X577570Y734118D03*
X580510Y724421D03*
X587170Y773768D03*
X579240Y775147D03*
X578802Y791476D03*
X574864D03*
X594920Y123370D03*
X595345Y120216D03*
X605070Y123991D03*
X600118Y112568D03*
X592938Y117657D03*
X595438Y138130D03*
X592938Y140689D03*
Y133232D03*
X594938Y127893D03*
X592491Y175906D03*
X593277Y179955D03*
X595707Y220995D03*
X591707Y230162D03*
X597074Y239995D03*
X600874Y239795D03*
X604774Y249795D03*
X596774D03*
X600874D03*
X604674Y239995D03*
X592874Y250995D03*
X605674Y236295D03*
X595374Y236795D03*
X592858Y247079D03*
X593459Y240780D03*
X594067Y265168D03*
X594174Y256695D03*
X593874Y262395D03*
X596574Y268695D03*
X600674Y268795D03*
X604574D03*
X604926Y278476D03*
X604774Y271893D03*
X590874Y275195D03*
X594374Y271395D03*
X596574Y276393D03*
X592201Y308988D03*
X593607Y305034D03*
X591977Y319360D03*
X590984Y323246D03*
X598551Y329541D03*
X601450Y326509D03*
X600770Y358702D03*
X605746Y387837D03*
X597440Y391690D03*
X605573Y393920D03*
X594860Y395088D03*
X600680Y412780D03*
X590720Y456076D03*
X591100Y450128D03*
X605800Y463167D03*
X603819Y485332D03*
X605798Y501238D03*
X598670Y508170D03*
X596751Y532108D03*
X603010Y527908D03*
X596560Y536108D03*
X606300Y551844D03*
X604820Y555040D03*
X596530Y574903D03*
X596495Y578903D03*
X592437Y566543D03*
X601043Y567781D03*
X596484Y582903D03*
X596209Y586903D03*
X590898Y597158D03*
X605396Y590552D03*
X605286Y584152D03*
X605290Y594166D03*
X593867Y595695D03*
X605521Y601097D03*
X590842Y608112D03*
X591023Y600384D03*
X605362Y609413D03*
X602314Y607641D03*
Y602641D03*
X593867Y600695D03*
X590646Y618751D03*
X605010Y641435D03*
X600980Y641533D03*
X594733Y653385D03*
X591279Y656223D03*
X596998Y658008D03*
X591840Y659568D03*
X596470Y655231D03*
X601588Y664798D03*
X602332Y671156D03*
X600736Y668425D03*
X593142Y663828D03*
X600719Y675156D03*
X597300Y663128D03*
X600690Y691896D03*
X600727Y681876D03*
X602020Y679156D03*
X600727Y686876D03*
X604220Y703774D03*
X600650Y707835D03*
X592960Y703291D03*
X592440Y723768D03*
X596860Y723422D03*
X601856Y711479D03*
X606146Y713145D03*
X601813Y715579D03*
X598880Y719232D03*
X595950Y708997D03*
X594170Y719290D03*
X601440Y735681D03*
X605938Y735665D03*
X596940Y735681D03*
X593004Y735662D03*
X603938Y753623D03*
X606270Y774615D03*
X597530Y780191D03*
X592480Y771514D03*
X598487Y791476D03*
X594550D03*
X618623Y108918D03*
X610543Y107678D03*
X617925Y114064D03*
X613432Y153528D03*
X608274Y249795D03*
X608774Y239995D03*
X610415Y237441D03*
X617778Y238873D03*
X608274Y268795D03*
X612974Y269095D03*
X609150Y328514D03*
X616490Y327534D03*
X613640Y336986D03*
X607671Y344818D03*
X619190Y336986D03*
X611848Y359784D03*
X607855Y352341D03*
X618581Y354818D03*
X609078Y388557D03*
X608869Y396959D03*
X608821Y403445D03*
X609078Y393557D03*
X612641Y397478D03*
Y402478D03*
X611050Y423087D03*
X611130Y417928D03*
X616258Y422211D03*
X610580Y448662D03*
X609370Y452974D03*
X610010Y456581D03*
X617980Y460408D03*
X621760Y526967D03*
X609300Y531638D03*
X613541Y546764D03*
X613470Y537495D03*
X616320Y537066D03*
X609168Y554851D03*
X610070Y557588D03*
X607077Y566915D03*
X610821Y566494D03*
X621937Y567143D03*
X609026Y579132D03*
X617270Y580443D03*
X611520Y596594D03*
X612493Y607666D03*
X611254Y617943D03*
X612370Y614143D03*
X615690Y625536D03*
X614579Y645072D03*
X616730Y633290D03*
X608310Y641603D03*
X611572Y629894D03*
X620510Y639427D03*
X616471Y636215D03*
X613796Y648705D03*
X612950Y656140D03*
X607620Y647169D03*
X615700Y657757D03*
X610651Y675156D03*
X614909Y671938D03*
X613200Y661577D03*
X620160Y670594D03*
X615940Y666862D03*
X617235Y689036D03*
X610693Y679333D03*
X612670Y681438D03*
X612811Y688422D03*
X621410Y696941D03*
X607020Y704644D03*
X608975Y708094D03*
X612914Y707630D03*
X610540Y697964D03*
X618020Y700000D03*
X607380Y699671D03*
X617930Y703520D03*
X620480Y693827D03*
X611244Y709830D03*
X621254Y713788D03*
X617093Y709167D03*
X609070Y721917D03*
X616070Y720838D03*
X613730Y717663D03*
X620670Y722216D03*
X620830Y717516D03*
X609840Y713617D03*
X619590Y735383D03*
X614732Y735517D03*
X608791Y735775D03*
X619080Y772610D03*
X619030Y778682D03*
X612260Y783106D03*
X609347Y778624D03*
X618172Y791476D03*
X614235D03*
X610298D03*
X628838Y120216D03*
X628738Y133012D03*
X624800Y184953D03*
Y179953D03*
X624358Y176090D03*
X632483Y192781D03*
X624950Y189801D03*
X632485Y202077D03*
X634962Y200121D03*
Y195121D03*
X622470Y261628D03*
X635000Y265400D03*
X634212Y281670D03*
X624101Y296525D03*
X624383Y292591D03*
X631672Y301066D03*
X632376Y305257D03*
X631702Y307880D03*
X632122Y312898D03*
X633773Y310439D03*
X635652Y313118D03*
X636962Y310928D03*
X623820Y321062D03*
X633470Y326710D03*
X628140Y317610D03*
X631860Y321455D03*
X627000Y327926D03*
X622890Y325227D03*
X633652Y315198D03*
X628141Y344818D03*
X630190Y336986D03*
X625190D03*
X637738Y392034D03*
X634511Y389156D03*
X633633Y403717D03*
X637614Y397259D03*
X630691Y405007D03*
X636938Y402885D03*
X633663Y411009D03*
X630691Y410007D03*
X636586Y410910D03*
X635840Y449890D03*
X626250Y450248D03*
X631280Y446007D03*
X635120Y456136D03*
X630570Y451450D03*
X634945Y461888D03*
X635545Y465888D03*
X622100Y465822D03*
X625900Y461769D03*
X628250Y471142D03*
X632680Y466669D03*
X636010Y469995D03*
X630420Y491511D03*
X636170Y493028D03*
X622600Y488753D03*
X622199Y506535D03*
X632157Y511230D03*
X625130Y534199D03*
X634530Y521565D03*
X634190Y538267D03*
X622798Y546764D03*
X632362Y565543D03*
X636890Y571351D03*
X624870Y573143D03*
X627084Y578257D03*
X634921Y580163D03*
X627047Y581066D03*
X636868Y593141D03*
X630768Y593241D03*
X624468D03*
Y612141D03*
X624368Y605941D03*
Y599741D03*
X629868Y612241D03*
X635968D03*
X623940Y628720D03*
X636890Y627095D03*
X629781Y628559D03*
X627986Y625895D03*
X630984Y624829D03*
X622510Y635544D03*
X634137Y631342D03*
X627146Y638932D03*
X623290Y641222D03*
X634137Y639352D03*
X630137Y639312D03*
X631930Y655254D03*
X634251Y683493D03*
X623940Y723503D03*
X633970Y723033D03*
X622290Y708516D03*
X628160Y722343D03*
X623960Y735141D03*
X628380Y735476D03*
X631690Y733744D03*
X635460Y735130D03*
X636170Y729335D03*
X630040Y745114D03*
X632300Y749755D03*
X636910Y745815D03*
X624010Y746351D03*
X629912Y769200D03*
X625010Y778281D03*
X636390Y775395D03*
X632030Y779137D03*
X632000Y775400D03*
X629983Y791476D03*
X633920D03*
X639957Y53849D03*
X638970Y132241D03*
X639200Y170100D03*
X639350Y250123D03*
X640448Y294422D03*
X643170Y294282D03*
X641227Y297070D03*
X644113Y297071D03*
X653352Y291388D03*
X642932Y284768D03*
X640112Y285042D03*
X649995Y296433D03*
X640171Y311965D03*
X644105D03*
X652362Y306598D03*
X651352Y323938D03*
X653162Y318398D03*
X650162D03*
X640647Y339854D03*
X648450Y338711D03*
X646013Y358110D03*
X639838Y349818D03*
X646171Y364676D03*
X648425Y373474D03*
X652139Y377125D03*
X647440Y386383D03*
X641236Y381616D03*
X645236Y377858D03*
X647340Y393283D03*
X647440Y408383D03*
X647340Y400083D03*
X651138Y417385D03*
X641480Y430289D03*
X650079D03*
X648208Y427819D03*
X643208D03*
X653070Y427500D03*
X650822Y425295D03*
X641690Y443656D03*
X647280Y446851D03*
X653360Y446280D03*
X651080Y455238D03*
X652110Y465238D03*
X651840Y460012D03*
X648920Y457851D03*
X646600Y463571D03*
X648956Y469323D03*
X646381Y478679D03*
X650521Y482930D03*
X647921Y475778D03*
X651395Y487265D03*
X646105Y492010D03*
X650790Y497730D03*
X650150Y494337D03*
X646906Y505210D03*
X638350Y507893D03*
X641842Y516730D03*
X646460Y512967D03*
X652690Y531693D03*
X640470Y523266D03*
X645040Y524444D03*
X645150Y535704D03*
X638166Y560972D03*
X638286Y557415D03*
X643012Y565243D03*
X651437Y569676D03*
X639673Y576888D03*
X651437Y578943D03*
X646732Y580781D03*
X641870Y580743D03*
X646870Y569443D03*
Y576243D03*
X643568Y593241D03*
Y612341D03*
Y606641D03*
Y599541D03*
X644636Y627257D03*
X642795Y624818D03*
X648701Y624774D03*
X638470Y639290D03*
X650928D03*
X646940Y643448D03*
X641263Y631393D03*
X649173Y629876D03*
X646737Y639413D03*
X642737D03*
X647870Y649784D03*
X646580Y654775D03*
X651226Y666288D03*
X639940Y687841D03*
X640330Y684439D03*
X642999Y685781D03*
X648077Y713569D03*
X644950Y719110D03*
X653500Y732583D03*
X639928Y738905D03*
X638890Y734879D03*
X652660Y749000D03*
X639920Y753526D03*
X646680Y755009D03*
X646500Y746300D03*
X650400Y770522D03*
X638470Y762212D03*
X649640Y757527D03*
X646370Y759252D03*
X647410Y767053D03*
X651690Y778099D03*
X640010Y778215D03*
X652212Y786700D03*
X659947Y53722D03*
X658769Y143630D03*
X658767Y151013D03*
X655642Y144915D03*
Y149915D03*
X658959Y165625D03*
X658972Y158337D03*
X655695Y159567D03*
Y164567D03*
X667300Y188112D03*
X660700Y203282D03*
X669250Y203317D03*
X665320Y203247D03*
X664560Y195018D03*
Y191443D03*
X660770Y214951D03*
X665390Y214916D03*
X661160Y235485D03*
X658582Y222614D03*
X658601Y229770D03*
X655030Y228744D03*
Y223744D03*
X661190Y246085D03*
X657838Y243407D03*
Y238407D03*
X660899Y311515D03*
X656270Y299379D03*
X654962Y307698D03*
X654060Y302459D03*
X659350Y298810D03*
X654352Y323938D03*
X655122Y315070D03*
X656730Y338633D03*
X666270Y359134D03*
X660138Y365885D03*
X659543Y377086D03*
X668925Y364887D03*
X663632Y366698D03*
X654340Y386283D03*
X661140D03*
X669215Y377488D03*
X654840Y408483D03*
X661940Y408383D03*
X666312Y417742D03*
X658295Y417662D03*
X653649Y417582D03*
X668779Y417135D03*
X655812Y424106D03*
X656021Y427864D03*
X665766Y427868D03*
X663339Y425601D03*
X658339D03*
X664450Y435739D03*
X658680Y446610D03*
X664528Y463432D03*
X667428D03*
X666928Y468132D03*
X660458Y470932D03*
X659828Y465162D03*
X667774Y477992D03*
X661158Y486152D03*
X667070Y483608D03*
X662780Y477039D03*
X660518Y492862D03*
X662630Y500823D03*
X654240Y511568D03*
X653800Y505331D03*
X659933Y513927D03*
X664024Y513414D03*
X668573Y514155D03*
X668823Y532470D03*
X668627Y527718D03*
X659740Y536019D03*
X667050Y535324D03*
X665170Y595943D03*
X661396Y588900D03*
X655445Y591918D03*
X664603Y601976D03*
X658980Y610043D03*
X655978Y609635D03*
X656070Y612743D03*
X655688Y601761D03*
X664870Y614543D03*
X654645Y627064D03*
X667610Y617197D03*
X663560Y625019D03*
X659600Y623785D03*
X655873Y615540D03*
X655170Y639432D03*
X654221Y631425D03*
X656971Y660492D03*
X657550Y655072D03*
X668000Y676595D03*
X659978Y666274D03*
X656254Y683277D03*
X663040Y688057D03*
X657340Y690286D03*
X655610Y706309D03*
X656505Y701191D03*
X654514Y720674D03*
X654050Y718086D03*
X656650Y713057D03*
X659200Y721454D03*
X659300Y734119D03*
X654000Y736400D03*
X656660Y736218D03*
X657570Y730414D03*
X658860Y727383D03*
X656000Y732400D03*
X657500Y761500D03*
X664460Y785890D03*
X657010Y786039D03*
X661479Y791476D03*
X665416D03*
X679927Y53881D03*
X675927Y53779D03*
X669987Y53672D03*
X670980Y77061D03*
X671810Y106472D03*
X670280Y188112D03*
X680220Y200725D03*
X678650Y203480D03*
X681770Y203514D03*
X680310Y217357D03*
X678750Y214908D03*
X681870Y214942D03*
X669320Y214986D03*
X671129Y305579D03*
X671166Y302550D03*
X679590Y352829D03*
X679430Y350013D03*
X672752Y366160D03*
X679552Y372873D03*
X677083Y375124D03*
X669540Y386283D03*
X678099Y389915D03*
X674235Y379364D03*
X677946Y387211D03*
X678986Y392661D03*
X669440Y395183D03*
Y408483D03*
X669540Y402783D03*
X678338Y405185D03*
X679138Y397985D03*
X680017Y403143D03*
X678838Y407785D03*
X673368Y416621D03*
X671056Y426300D03*
X683128Y451332D03*
X680228Y451432D03*
X672660Y441007D03*
X673740Y449887D03*
X682764Y444832D03*
X677070Y444820D03*
X670428Y463532D03*
X669728Y468032D03*
X672628D03*
X672190Y457216D03*
X683112Y479786D03*
X679299Y491473D03*
X684876Y497385D03*
X674156Y503662D03*
X678450Y508438D03*
X680790Y504521D03*
X677160Y529422D03*
X675044Y524581D03*
X678315Y540752D03*
X684620Y535923D03*
X678217Y536752D03*
X670940Y612070D03*
X683720Y631732D03*
X681310Y666671D03*
X671400Y666151D03*
X678386Y668420D03*
X673386D03*
X669390Y695406D03*
X672630Y720752D03*
X675100Y749300D03*
X672710Y746235D03*
X672500Y749179D03*
X676390Y778439D03*
X677490Y782114D03*
X673290Y782855D03*
X677227Y786454D03*
X669320Y783845D03*
X681480Y777388D03*
X681164Y783461D03*
X669810Y786721D03*
X672500Y779579D03*
X683520Y792080D03*
X688160Y64459D03*
X689500Y120441D03*
X691148Y140140D03*
X698150Y136791D03*
X691280Y149571D03*
X691314Y145071D03*
X687546Y154228D03*
X699990Y149631D03*
X700060Y144981D03*
X687571Y172292D03*
X689820Y200159D03*
Y203491D03*
X691970Y216820D03*
X691690Y212100D03*
X693540Y205721D03*
X697800Y205879D03*
X692010Y221158D03*
X687584Y233034D03*
Y251770D03*
X689864Y392130D03*
X686686Y392522D03*
X687869Y386780D03*
X688118Y381043D03*
X687121Y407004D03*
X689864Y398141D03*
X686686Y397522D03*
X689527Y407843D03*
X685859Y403970D03*
X691037Y401739D03*
X686731Y413349D03*
X689527Y412843D03*
X687130Y464132D03*
X691070Y464058D03*
X689017Y497282D03*
X694823Y498932D03*
X691161Y518684D03*
X692520Y506898D03*
X696494Y513677D03*
X689729Y509580D03*
X696891Y507279D03*
X700719Y516954D03*
X686661Y519199D03*
X698438Y524890D03*
X686770Y543325D03*
X694150Y536155D03*
X690040Y535797D03*
X687183Y539585D03*
X691532Y559789D03*
Y563789D03*
Y567789D03*
Y571789D03*
Y575789D03*
Y579789D03*
Y583789D03*
Y587789D03*
X695600Y590788D03*
X685410Y621250D03*
X688340Y621294D03*
X687660Y631799D03*
X685640Y634154D03*
X692720Y670540D03*
X698830Y670652D03*
X698386Y667241D03*
X693386D03*
X689100Y680291D03*
X688510Y735294D03*
X699600Y776000D03*
X689700Y774500D03*
X707176Y50574D03*
X711676Y51019D03*
X706380Y75482D03*
X708130Y106389D03*
X701687Y212132D03*
X700947Y216868D03*
X700994Y221368D03*
X701770Y331938D03*
X707942Y448676D03*
X714639Y454872D03*
X712239Y452293D03*
X702730Y455483D03*
X704550Y444407D03*
X715528Y459332D03*
X710768Y475972D03*
X715328Y481122D03*
X704766Y498880D03*
X713978Y498075D03*
X716021Y516945D03*
X700829Y504041D03*
X707736Y510140D03*
X707920Y505575D03*
X712281Y525785D03*
X706361Y532632D03*
X716260Y525295D03*
X712820Y519647D03*
X710585Y539103D03*
X701170Y538508D03*
X708258Y549815D03*
X701023Y553658D03*
X710873Y563230D03*
X713300Y578995D03*
X713190Y583032D03*
X712740Y593101D03*
X715282Y620282D03*
X711612Y620383D03*
X712732Y631749D03*
X716064D03*
X713742Y634373D03*
X703570Y673036D03*
X707660Y673204D03*
X708386Y669774D03*
X703386D03*
X713910Y681330D03*
X713445Y677641D03*
X708450Y695489D03*
X705870Y721832D03*
X709500Y736800D03*
X706575Y740425D03*
X704000Y770800D03*
X716245Y765576D03*
X704786Y791274D03*
X708723Y791092D03*
X709040Y787507D03*
X719800Y24920D03*
X726160Y109316D03*
X726190Y105325D03*
X726160Y112508D03*
X726500Y123466D03*
X726400Y130303D03*
X726470Y126659D03*
X731566Y442136D03*
X726580Y455637D03*
X731570Y464043D03*
X726430Y465371D03*
X726830Y460815D03*
X727940Y469943D03*
X731340Y476723D03*
X720140Y478333D03*
X718431Y483368D03*
X721290Y484381D03*
X719370Y472436D03*
X725730Y486788D03*
X729640Y486848D03*
X720150Y491632D03*
X729942Y515757D03*
X719332D03*
X719761Y532432D03*
X720052Y620480D03*
X719092Y631682D03*
X717372Y634474D03*
X727830Y641829D03*
X728690Y649829D03*
X718510Y681526D03*
X721100Y689400D03*
X718445Y677641D03*
X731200Y716200D03*
X729500Y737400D03*
X730800Y728400D03*
X729500Y746300D03*
X718150Y763015D03*
X721100Y762903D03*
X721245Y765576D03*
X727570Y775278D03*
X730990Y775334D03*
X726925Y778490D03*
X731925D03*
X721790Y791408D03*
X722590Y787885D03*
X738620Y109351D03*
X738650Y105360D03*
X738620Y112543D03*
X738370Y123395D03*
X738270Y130232D03*
X738340Y126588D03*
X747080Y129815D03*
X747600Y323527D03*
X745220Y327250D03*
X741401Y454832D03*
X736310Y450774D03*
X737350Y464330D03*
Y459823D03*
X742779Y487639D03*
X743364Y478975D03*
X743150Y483502D03*
X738130Y502748D03*
X732817Y489435D03*
X734575Y492575D03*
X745500Y492500D03*
X744020Y566143D03*
X744090Y575066D03*
X743951Y578833D03*
X744050Y571834D03*
X747470Y585542D03*
X747460Y582318D03*
X744000Y647919D03*
X733210Y645829D03*
X732540Y653829D03*
X734460Y788654D03*
Y791654D03*
X762590Y106529D03*
X762630Y103302D03*
X754580Y124020D03*
X754610Y127247D03*
X750930Y129815D03*
X750430Y314330D03*
X750350Y311343D03*
X750700Y323771D03*
X753230Y328262D03*
X759400Y334839D03*
X754850Y335055D03*
X755500Y337791D03*
X758223Y446532D03*
X757823Y451032D03*
X758494Y455532D03*
X748723Y455332D03*
X758500Y469500D03*
X757500Y474000D03*
X748300Y496800D03*
X751730Y583047D03*
X752960Y653967D03*
X749520Y658372D03*
X765250Y357789D03*
X765610Y361194D03*
X766840Y561290D03*
X766920Y564080D03*
X766950Y558318D03*
X766820Y569897D03*
X766900Y567233D03*
Y572869D03*
X771110Y578643D03*
X770850Y575760D03*
X770710Y584054D03*
X770850Y587025D03*
G54D16*
X10859Y109561D03*
X20859D03*
X83740Y20708D03*
X78740Y30708D03*
X73740Y20708D03*
X507489Y360278D03*
X713661Y20708D03*
X708661Y30708D03*
X703661Y20708D03*
X712975Y155655D03*
Y165455D03*
Y173455D03*
Y183255D03*
Y234461D03*
Y244261D03*
Y252261D03*
Y262061D03*
X723275Y155655D03*
Y165455D03*
Y173455D03*
Y183255D03*
Y234461D03*
Y244261D03*
Y252261D03*
Y262061D03*
G54D32*
X399606Y377165D03*
X413386Y363385D03*
X403543Y367322D03*
Y387008D03*
X413386Y390945D03*
X427166Y377165D03*
X423229Y367322D03*
Y387008D03*
G54D21*
X40749Y150808D03*
Y249194D03*
G54D38*
X546181Y81889D03*
G54D11*
X-44872Y125213D03*
Y141213D03*
Y232533D03*
D03*
Y248533D03*
D03*
Y738493D03*
Y754493D03*
X-26872Y125213D03*
Y141213D03*
Y232533D03*
D03*
Y248533D03*
D03*
Y738493D03*
Y754493D03*
G54D19*
X36024Y187233D03*
Y181225D03*
Y205257D03*
Y199249D03*
Y193241D03*
Y217272D03*
Y211264D03*
X41930Y184229D03*
Y178221D03*
Y202253D03*
Y196245D03*
Y190237D03*
Y220276D03*
Y214268D03*
Y208260D03*
G54D28*
X154307Y507507D03*
X154517Y513931D03*
X154038Y511386D03*
X153967Y517186D03*
X159185Y531356D03*
X153731Y520734D03*
X162335Y521906D03*
X155400Y533436D03*
X154246Y527468D03*
X162335Y528206D03*
X159186Y534504D03*
X159185Y543953D03*
X155060Y545526D03*
X154945Y542383D03*
Y536083D03*
Y539233D03*
X159185Y547103D03*
X154900Y548682D03*
X162315Y553391D03*
X154900Y551832D03*
X159186Y553402D03*
X157611Y557468D03*
X154410Y557990D03*
X178818Y274540D03*
X178085Y518755D03*
X168617Y525756D03*
X172371Y519783D03*
X174720Y531356D03*
X178117Y528187D03*
X178082Y537654D03*
X178099Y550267D03*
X174105Y542290D03*
X167027Y539526D03*
Y536376D03*
X173217Y536556D03*
X181818Y274540D03*
X186417Y518526D03*
X186467Y514036D03*
X184920Y508626D03*
X181232Y515607D03*
X187417Y508756D03*
X189007Y514846D03*
X181232Y528205D03*
X187875Y534128D03*
X181232Y543953D03*
X184384Y537656D03*
X181232Y537654D03*
X184384Y543955D03*
X188927Y537836D03*
X190434Y546870D03*
X188383Y556895D03*
X184386Y553406D03*
X208050Y528883D03*
X209886Y539962D03*
X201509Y539853D03*
X207309Y539953D03*
X199709Y551653D03*
X208109Y551053D03*
X216184Y268587D03*
X214626Y516492D03*
X227326Y505741D03*
X227329Y508894D03*
X223709Y505353D03*
X216564Y528902D03*
X214118Y528583D03*
X218751Y543835D03*
X233626Y502591D03*
X230476D03*
X243075D03*
X230476Y505741D03*
X236776Y508891D03*
Y518339D03*
X233626Y515190D03*
X230476D03*
X233626Y518339D03*
X236776Y512040D03*
X243075Y508891D03*
X230476D03*
X236776Y515190D03*
X230476Y518339D03*
Y512040D03*
X239925Y518339D03*
X233626Y521489D03*
Y527788D03*
X230476Y534087D03*
X236776Y521489D03*
Y527788D03*
Y524639D03*
X230476D03*
X233626Y534087D03*
X239925Y527788D03*
Y524639D03*
X230476Y527788D03*
Y521489D03*
X239925Y534087D03*
Y521489D03*
X233626Y543536D03*
X236776Y537236D03*
X230476D03*
Y543536D03*
Y540386D03*
X233626D03*
X236776Y543536D03*
X233626Y537236D03*
X239925D03*
X243075Y559284D03*
Y552984D03*
X231209Y566282D03*
X252524Y502591D03*
X255673D03*
X249374D03*
X246224D03*
X255673Y508891D03*
Y505741D03*
X249374D03*
Y508891D03*
X252524Y505741D03*
Y508891D03*
X249374Y512040D03*
X246224D03*
X252524Y527789D03*
Y524639D03*
X255673Y534088D03*
X252524D03*
X249374D03*
X255673Y524639D03*
Y527789D03*
X249374D03*
Y524639D03*
X255673Y537237D03*
X249374D03*
X252524D03*
X255673Y540387D03*
X249374D03*
X252524D03*
X249374Y549835D03*
X255673Y565580D03*
Y552984D03*
Y556133D03*
Y559282D03*
Y562431D03*
X249344Y552984D03*
Y556134D03*
X246224Y559284D03*
Y556134D03*
Y562434D03*
X252554Y559314D03*
X262904Y293850D03*
X268943Y291086D03*
X265122Y502591D03*
X274582D03*
X271402Y499441D03*
X271429Y496295D03*
X261972Y502591D03*
X268272Y505741D03*
Y508891D03*
X265121D03*
X261972D03*
Y505741D03*
X265122Y512040D03*
X261972D03*
X265122Y505741D03*
X261972Y521489D03*
X268272Y534088D03*
X265122D03*
X261972D03*
X268272Y524639D03*
Y527789D03*
X265122D03*
Y524639D03*
X261972D03*
Y527789D03*
X268272Y521489D03*
X265122D03*
X268272Y540387D03*
X265122D03*
X261972D03*
X265122Y537237D03*
X268272D03*
X261972D03*
X265122Y549836D03*
X261972D03*
X274571Y552985D03*
X265122D03*
X268272Y559291D03*
X271422Y562434D03*
X271421Y556135D03*
X271422Y559291D03*
X261973Y552985D03*
X262009Y556153D03*
X261972Y562431D03*
X271422Y565583D03*
X271421Y552985D03*
X274572Y556142D03*
X284024Y499445D03*
X287173D03*
X277712Y502595D03*
X290323Y534092D03*
X280874D03*
X287174D03*
X284024D03*
X277725Y521493D03*
X280874Y537241D03*
Y543541D03*
X284024D03*
X287174Y540391D03*
X290323D03*
X290322Y549841D03*
X280872D03*
X287174Y559289D03*
X284024Y565588D03*
X287174D03*
X290323Y556140D03*
X287174Y562438D03*
X280874D03*
X284024D03*
Y559289D03*
X280874D03*
X277725Y556135D03*
Y559289D03*
X287174Y556139D03*
X280874Y552989D03*
X287174D03*
X284024D03*
X293473Y534092D03*
Y540391D03*
Y559290D03*
X679175Y464038D03*
X674353Y463842D03*
X683112Y464038D03*
Y483723D03*
X683113Y471941D03*
X683112Y487660D03*
X687049Y467975D03*
X698860D03*
X690986D03*
X698860Y471912D03*
X690986D03*
Y479786D03*
X687049Y483723D03*
X698860Y479786D03*
Y483723D03*
X687049Y479786D03*
X690986Y483723D03*
X687049Y471912D03*
X698683Y487517D03*
X690986Y487660D03*
X687049D03*
X692955Y502112D03*
X702797Y464038D03*
Y467975D03*
X706734Y471913D03*
Y483723D03*
X710671Y479786D03*
X706734Y475850D03*
X710671Y471913D03*
X702585Y483749D03*
X702797Y471912D03*
Y479786D03*
X706734D03*
G54D31*
X354348Y38554D03*
X393718D03*
G54D36*
X507489Y281538D03*
G54D43*
X605796Y174845D03*
Y189845D03*
Y204845D03*
X611702Y185690D03*
Y178997D03*
Y200690D03*
Y193997D03*
G54D40*
X590999Y69167D03*
Y77041D03*
Y84915D03*
X615657Y69167D03*
Y77041D03*
Y84915D03*
G54D37*
X514780Y28803D03*
X524780D03*
X514780Y38803D03*
X524780D03*
X534780Y28803D03*
X544780D03*
X534780Y38803D03*
X544780D03*
X554780Y28803D03*
Y38803D03*
X577371Y28803D03*
X587371D03*
X577371Y38803D03*
X587371D03*
X597371Y28803D03*
Y38803D03*
X607371D03*
X617371Y28803D03*
Y38803D03*
X639963Y28803D03*
Y38803D03*
X649963Y28803D03*
Y38803D03*
X659963Y28803D03*
Y38803D03*
X669963D03*
X679963Y28803D03*
Y38803D03*
G54D24*
X80490Y420690D03*
Y423690D03*
X86050Y428718D03*
X80490Y426690D03*
X79900Y439193D03*
X86050Y437470D03*
Y434470D03*
X79900Y445193D03*
Y442193D03*
X86050Y443432D03*
Y446432D03*
X84990Y563286D03*
X82140Y560758D03*
X81980Y556851D03*
X81516Y577905D03*
X83030Y582656D03*
X85140Y585213D03*
X90031Y421693D03*
X90238Y418623D03*
X88200Y568111D03*
X243743Y636514D03*
X251803Y636704D03*
X254773Y644424D03*
X254303Y636744D03*
X256463Y639364D03*
X252173Y644344D03*
X249083Y636664D03*
X256513Y642494D03*
X246553Y636684D03*
X321357Y456709D03*
X321246Y472669D03*
X374207Y479329D03*
X374203Y491029D03*
X414870Y455166D03*
Y450976D03*
X421710Y424527D03*
X430340Y416573D03*
X432450Y418766D03*
X422120Y418288D03*
X432960Y414886D03*
X422080Y414644D03*
Y410454D03*
X421770Y433187D03*
X422860Y441790D03*
X422760Y445581D03*
X425870Y449509D03*
X422460Y449467D03*
X429670Y449552D03*
X419420Y453168D03*
Y457358D03*
X446660Y413325D03*
X446950Y417162D03*
X438390Y456129D03*
X438520Y452324D03*
X433720Y449467D03*
X588540Y557418D03*
X604437Y557956D03*
X596050Y557563D03*
X596401Y589852D03*
X621937Y558276D03*
X621840Y555040D03*
X609060Y552101D03*
X612270Y586543D03*
G54D29*
X175921Y301920D03*
X178921D03*
X188418Y278887D03*
X191054Y294424D03*
X183254Y295023D03*
X181921Y301920D03*
X191949Y301987D03*
X188810Y301998D03*
X187907Y308784D03*
X209449Y281098D03*
Y287398D03*
Y290548D03*
X203149Y287398D03*
X206299D03*
X196867Y294342D03*
X198880Y310245D03*
X196812Y308619D03*
X227517Y244187D03*
X225973Y265197D03*
X218899Y281098D03*
X225160Y293676D03*
X225199Y290548D03*
Y284248D03*
X222049Y287398D03*
X212599D03*
X215749Y290548D03*
X225199Y306298D03*
Y312598D03*
X222049Y306298D03*
X218899D03*
X222049Y299998D03*
X212610Y306305D03*
X241613Y265197D03*
X233793Y266697D03*
Y257697D03*
X233904Y252772D03*
X234649Y281098D03*
X237865Y281131D03*
X231450Y290583D03*
X237760Y293692D03*
X237799Y287398D03*
X240949Y290548D03*
Y287398D03*
X231499Y284248D03*
Y296848D03*
Y293698D03*
Y299998D03*
X237799Y312598D03*
X231499D03*
X240949Y309448D03*
X231567Y321742D03*
X232782Y327096D03*
X259518Y252358D03*
X249433Y257697D03*
X246467Y255442D03*
X244099Y281098D03*
X254234Y281622D03*
X250399Y281098D03*
X244110Y290505D03*
X257447Y287117D03*
X244099Y287398D03*
X250399D03*
X253549Y290548D03*
X247249Y296848D03*
X244099D03*
X258590Y311560D03*
X247290Y327694D03*
X253710Y315669D03*
X267268Y311642D03*
X264287Y311687D03*
X270518Y311637D03*
X276386Y311687D03*
X310623Y313589D03*
X313123D03*
X320623D03*
X318123D03*
X315623D03*
X323123D03*
X351964Y599332D03*
X360647Y602636D03*
X354973Y605588D03*
Y602588D03*
Y611588D03*
X361473Y620588D03*
X354973Y614588D03*
Y620588D03*
Y623588D03*
X401091Y587054D03*
X398386Y587126D03*
X401422Y597270D03*
Y599770D03*
X398822Y600399D03*
X412960Y618207D03*
X410315Y614782D03*
X436370Y410543D03*
X444020Y410374D03*
X439830D03*
X440900Y446260D03*
X436710D03*
X444850Y446337D03*
G54D33*
X414961Y98622D03*
X605796Y165160D03*
X609733Y215672D03*
G54D18*
X23628Y321764D03*
Y338300D03*
X45282Y321764D03*
Y338300D03*
X434102Y232640D03*
Y311875D03*
X583913Y69167D03*
X608571D03*
G54D23*
X76880Y143269D03*
X86880D03*
X739968Y29361D03*
X749968D03*
G54D27*
X151969Y98622D03*
G54D22*
X43898Y168544D03*
Y231457D03*
G54D41*
X590999Y92789D03*
X615657D03*
G54D45*
X711575Y143555D03*
Y195355D03*
Y222361D03*
Y274161D03*
X733975Y143555D03*
Y195355D03*
Y222361D03*
Y274161D03*
G54D17*
X25439Y303260D03*
Y356804D03*
G54D35*
X481102Y34528D03*
G54D44*
X688977Y105315D03*
Y719488D03*
G54D25*
X98426Y105512D03*
Y719685D03*
G54D26*
X102362Y247244D03*
Y349606D03*
X354331Y247244D03*
Y349606D03*
G54D34*
X413386Y377165D03*
G54D20*
X50981Y58681D03*
X46981Y58690D03*
X162786Y568599D03*
X160699Y587904D03*
X166786Y569056D03*
X175386Y569589D03*
X179740Y568951D03*
X178416Y587849D03*
X196410Y650155D03*
X187410Y649715D03*
Y659705D03*
X191910Y650055D03*
X209590Y580893D03*
X197130Y626135D03*
X200910Y650155D03*
X205410Y650035D03*
X219309Y489353D03*
X222209D03*
X215604Y621977D03*
X271720Y422587D03*
X269630Y424884D03*
X274180Y424966D03*
X276400Y422341D03*
X280010Y422279D03*
X281190Y424966D03*
X278080Y424760D03*
X551341Y274262D03*
X569682Y195199D03*
X572782D03*
X728661Y558934D03*
X731251Y558975D03*
X726154Y559002D03*
X720445Y558990D03*
X723370Y558906D03*
G54D14*
X-35858Y731383D03*
X17020Y592934D03*
X15850Y610980D03*
X34140Y540345D03*
X34240Y536966D03*
X28270Y602194D03*
X33140Y602232D03*
X54117Y529098D03*
X41957Y543321D03*
X39360Y604593D03*
X60318Y65593D03*
X58000Y412641D03*
X64568Y451029D03*
X67568D03*
X70568D03*
X86479Y249259D03*
X86050Y425112D03*
X85617Y451275D03*
X82617D03*
X81174Y503587D03*
X81635Y521104D03*
X102257Y167955D03*
X88399Y244041D03*
X88617Y451275D03*
X143252Y573105D03*
X168370Y477790D03*
X202518Y673273D03*
X197889Y671226D03*
X201411Y708231D03*
X224108Y388029D03*
X228242Y463681D03*
X223953Y463550D03*
X212809Y479053D03*
X215409Y479253D03*
X218308Y635939D03*
X225179Y642614D03*
X225237Y671772D03*
X230749Y160807D03*
X230650Y164566D03*
X230890Y169424D03*
X231000Y173381D03*
X230100Y187389D03*
X230140Y197240D03*
X239228Y393291D03*
X235319Y464362D03*
X233309Y472553D03*
X237609Y472453D03*
X241909Y472553D03*
X234370Y593242D03*
X250401Y315713D03*
X256532Y384895D03*
X255509Y472253D03*
X246109Y472465D03*
X251309Y472553D03*
X252036Y582131D03*
X253187Y596382D03*
X274580Y74281D03*
X269920Y74318D03*
X272440Y76177D03*
X268080Y76416D03*
X268702Y107928D03*
X273477Y385100D03*
X261663Y385193D03*
X273509Y471649D03*
X260609Y472453D03*
X264909Y472553D03*
X269109Y472353D03*
X275452Y483219D03*
X273480Y589201D03*
X269609Y588653D03*
X272460Y687889D03*
X272650Y693742D03*
X287270Y75018D03*
X283870Y74724D03*
X279100Y74447D03*
X289738Y76173D03*
X285543Y76867D03*
X281400Y75938D03*
X276969Y76247D03*
X287599Y108831D03*
X278880Y108482D03*
X288687Y385290D03*
X281864Y386178D03*
X284687Y386769D03*
X283650Y589044D03*
X278109Y589238D03*
X279090Y668504D03*
X279785Y663876D03*
X275560Y697804D03*
X279060Y693306D03*
X292313Y76345D03*
X305880Y76361D03*
X299220Y76196D03*
X302953Y76167D03*
X295867Y76567D03*
X299590Y121289D03*
X299850Y124708D03*
X303171Y374224D03*
X291686Y375177D03*
X291382Y385457D03*
X302870Y633981D03*
X297162Y642065D03*
X304870Y655747D03*
X306294Y659156D03*
Y667156D03*
Y663156D03*
Y675156D03*
Y671156D03*
X305979Y691156D03*
X306145Y683156D03*
X305979Y687156D03*
X306294Y679156D03*
X317334Y10955D03*
X322640Y9774D03*
X317334Y28955D03*
X318910Y74595D03*
X314310Y74540D03*
X307740Y74263D03*
X309730Y76232D03*
X321283Y76327D03*
X316623Y76047D03*
X312402Y76587D03*
X313583Y122387D03*
X314940Y642067D03*
X323334Y12377D03*
X323871Y25812D03*
Y16812D03*
Y19812D03*
Y28812D03*
X327117Y31840D03*
X323640Y74393D03*
X326140Y76196D03*
X336010Y531598D03*
X327540Y653432D03*
X343430Y385937D03*
X346862Y424850D03*
X351722Y659319D03*
X353902Y667128D03*
X355250Y420679D03*
X361562Y645175D03*
X361650Y658537D03*
X361580Y652755D03*
X361660Y671306D03*
X361510Y680886D03*
X362040Y684875D03*
X361580Y703860D03*
X363590Y702324D03*
X373538Y520213D03*
X376528Y520138D03*
X385410Y566122D03*
X383034Y640267D03*
X379093Y657739D03*
X376650Y654157D03*
X377211Y673197D03*
X379791Y679454D03*
X392600Y20548D03*
X389240D03*
X397790Y69610D03*
X392076Y470970D03*
X396048Y540127D03*
X395922Y536127D03*
X400589Y611672D03*
X400587Y607022D03*
X398195Y620821D03*
X400695Y618321D03*
X398195D03*
X400695Y620821D03*
X392063Y624109D03*
X395701Y637430D03*
X399440Y637340D03*
X386173Y665065D03*
X391938Y672320D03*
X392097Y676231D03*
X400408Y681193D03*
X409985Y508431D03*
X405234Y611692D03*
X405249Y607017D03*
X405426Y626809D03*
X409520Y637387D03*
X414760Y636225D03*
X410918Y649363D03*
X412250Y683196D03*
X424904Y586283D03*
X419221Y612253D03*
X425151Y608429D03*
X420245Y636004D03*
X417422Y637592D03*
X422007Y652732D03*
X423623Y645396D03*
X422026Y656883D03*
X422222Y675226D03*
X426100Y667884D03*
X427900Y679709D03*
X430861Y679156D03*
X430862Y691156D03*
X430813Y687156D03*
X430618Y699156D03*
X430667Y703156D03*
X430731Y707156D03*
X430813Y695156D03*
X430738Y711156D03*
X435972Y655595D03*
X436000Y675706D03*
X435539Y671628D03*
X436445Y667628D03*
X454763Y183503D03*
X453340Y185670D03*
X457482Y183523D03*
X459000Y200500D03*
X463565Y515723D03*
X455890Y592792D03*
X471500Y138000D03*
X478000Y212500D03*
X467677Y510055D03*
X467496Y513179D03*
X466587Y515764D03*
X467586Y506807D03*
X471190Y593964D03*
X474946Y659376D03*
X479409Y682305D03*
X492955Y99440D03*
X487740Y161235D03*
X487464Y198566D03*
X491320Y231809D03*
X485510Y536673D03*
X491380Y639279D03*
X495900Y641804D03*
X492310Y650516D03*
X482180Y646278D03*
X491044Y667604D03*
X491060Y671604D03*
X492294Y682347D03*
X483056Y679628D03*
X491167Y687507D03*
X491067Y699656D03*
X491380Y694656D03*
X502183Y156709D03*
X500963Y162261D03*
X499225Y205296D03*
X499405Y242877D03*
X507000Y239000D03*
X498920Y523803D03*
X503958Y529405D03*
X500098Y608885D03*
X509238Y608515D03*
X504836Y657097D03*
X503680Y659666D03*
X498040Y675306D03*
X498870Y668324D03*
X506376Y687436D03*
X500710Y706582D03*
X499842Y710582D03*
X499452Y714582D03*
X518725Y170525D03*
X512160Y217073D03*
X515675Y234555D03*
X524675Y234766D03*
X517189Y226229D03*
X515413Y590950D03*
X525570Y602466D03*
X511910Y638722D03*
X526610Y672286D03*
X542180Y93534D03*
X529272Y178311D03*
X542002Y180100D03*
X538525Y213425D03*
X536972Y242993D03*
X536476Y238993D03*
X540701Y590162D03*
X527638Y590325D03*
X541980Y620227D03*
X539471Y632476D03*
X541440Y647594D03*
X531970Y650491D03*
X539120Y670129D03*
X543193Y710787D03*
X547480Y96632D03*
X555836Y179259D03*
X546000Y180000D03*
X549909Y207060D03*
X557909Y207537D03*
X555750Y212029D03*
X550040Y243929D03*
X557207Y274828D03*
X549760Y407251D03*
X553230D03*
X553750Y410420D03*
X551161Y547148D03*
X545138Y539725D03*
X551338Y551100D03*
X551238Y571725D03*
X547000Y590163D03*
X555356Y665156D03*
Y669156D03*
X555308Y673156D03*
X555357Y689156D03*
X555284Y685156D03*
X555235Y681156D03*
X555308Y677156D03*
X555150Y697156D03*
X555271Y693156D03*
X547542Y711523D03*
X565938Y96820D03*
X569874Y231795D03*
X567493Y532225D03*
X566053Y627509D03*
X588943Y98963D03*
X589308Y103990D03*
X587968Y138765D03*
X583707Y220762D03*
X587707Y220728D03*
X584413Y563198D03*
X583538Y552225D03*
X578110Y582149D03*
X582023Y571242D03*
X578399Y585696D03*
X585500Y620926D03*
X579020Y658250D03*
X579151Y707857D03*
X588151D03*
X584101Y707893D03*
X603158Y91535D03*
X601374Y94048D03*
X604543Y94886D03*
X598123Y102023D03*
X595318Y98854D03*
X593850Y103755D03*
X592392Y100623D03*
X593537Y161023D03*
X592917Y171906D03*
X591707Y221095D03*
X604338Y338285D03*
X608306Y359971D03*
X617592Y362539D03*
X620238Y364369D03*
X619014Y408353D03*
X621399Y420400D03*
X610570Y691156D03*
X610550Y686640D03*
X610810Y683933D03*
X610570Y695156D03*
X626380Y85117D03*
X624020Y83243D03*
X623750Y87130D03*
X626380Y88518D03*
X623725Y90422D03*
X626180Y91919D03*
X623820Y93654D03*
X626320Y96084D03*
X623610Y97125D03*
X626180Y99276D03*
X624889Y357778D03*
X636990Y386464D03*
X627022Y383713D03*
X633455Y427209D03*
X634578Y424964D03*
X643957Y53688D03*
X648838Y349785D03*
X642863Y358010D03*
X648493Y417221D03*
X655947Y53677D03*
X662390Y377039D03*
X653938Y364885D03*
X663674Y417999D03*
X665050Y680648D03*
X657320Y723584D03*
X655574Y728674D03*
X676590Y188198D03*
X680100Y188182D03*
X682140Y191214D03*
Y194615D03*
X678360Y557426D03*
X673950Y557314D03*
X677850Y562515D03*
X673700D03*
X677730Y567706D03*
X673590Y567696D03*
X684500Y786665D03*
X683520Y789080D03*
X693520Y186376D03*
X697850Y186441D03*
X689480Y191144D03*
Y194615D03*
X727602Y500100D03*
X744760Y103711D03*
X744790Y106938D03*
X747710Y100293D03*
X745070Y110183D03*
X751080Y100293D03*
X748070Y110209D03*
X751180D03*
G54D30*
X233626Y508891D03*
X239925Y540386D03*
Y543536D03*
X255673Y512040D03*
X252524D03*
Y549835D03*
X255673D03*
X268272Y512040D03*
X271422D03*
X268272Y549836D03*
X271421D03*
X277725Y534092D03*
Y527792D03*
Y540391D03*
Y543541D03*
Y537241D03*
G54D39*
X556181Y81889D03*
G54D42*
X607371Y28803D03*
X669963D03*
%LPC*%
G75*
G36*
G01X-36897Y131113D02*
G02X-34847I1025J-400D01*
G01X-33897D01*
G02Y130313I1025J-400D01*
G01X-34847D01*
G02X-36897I-1025J400D01*
G01X-37847D01*
G02Y131113I-1025J400D01*
G01X-36897D01*
G37*
G36*
G01Y238433D02*
G02X-34847I1025J-400D01*
G01X-33897D01*
G02Y237633I1025J-400D01*
G01X-34847D01*
G02X-36897I-1025J400D01*
G01X-37847D01*
G02Y238433I-1025J400D01*
G01X-36897D01*
G37*
G36*
G01X-34847D02*
G03X-36897I-1025J-400D01*
G01X-37847D01*
G03Y237633I-1025J-400D01*
G01X-36897D01*
G03X-34847I1025J400D01*
G01X-33897D01*
G03Y238433I1025J400D01*
G01X-34847D01*
G37*
G36*
G01Y748593D02*
G02X-36897I-1025J400D01*
G01X-37847D01*
G02Y749393I-1025J400D01*
G01X-36897D01*
G02X-34847I1025J-400D01*
G01X-33897D01*
G02Y748593I1025J-400D01*
G01X-34847D01*
G37*
G54D46*
G01X38493Y-241864D02*
Y-246864D01*
G01X37036Y-241864D02*
X39950D01*
G01X44860Y-246864D02*
X42326D01*
Y-241864D01*
X44860D01*
G01X43846Y-244281D02*
X42326D01*
G01X47426Y-241864D02*
Y-246864D01*
X49960D01*
G01X53793Y-247031D02*
X53666Y-246947D01*
Y-246781D01*
X53793Y-246697D01*
X53920Y-246781D01*
Y-246947D01*
X53793Y-247031D01*
G01Y-244781D02*
X53666Y-244697D01*
Y-244531D01*
X53793Y-244447D01*
X53920Y-244531D01*
Y-244697D01*
X53793Y-244781D01*
G01X58576Y-248531D02*
X57943Y-247697D01*
X57626Y-246864D01*
Y-243531D01*
X57943Y-242697D01*
X58576Y-241864D01*
G01X63993D02*
X63486Y-242031D01*
X63106Y-242447D01*
X62853Y-242947D01*
X62663Y-243614D01*
X62600Y-244364D01*
X62663Y-245114D01*
X62853Y-245781D01*
X63106Y-246281D01*
X63486Y-246697D01*
X63993Y-246864D01*
X64500Y-246697D01*
X64880Y-246281D01*
X65133Y-245781D01*
X65323Y-245114D01*
X65386Y-244364D01*
X65323Y-243614D01*
X65133Y-242947D01*
X64880Y-242447D01*
X64500Y-242031D01*
X63993Y-241864D01*
G01X67700Y-245864D02*
X68080Y-246447D01*
X68586Y-246781D01*
X69156Y-246864D01*
X69663Y-246781D01*
X70170Y-246364D01*
X70486Y-245864D01*
X70550Y-245364D01*
X70423Y-244781D01*
X69980Y-244364D01*
X69536Y-244197D01*
X68966D01*
G01X69536D02*
X69916Y-243947D01*
X70233Y-243531D01*
X70360Y-243031D01*
X70233Y-242531D01*
X69916Y-242114D01*
X69346Y-241864D01*
X68776Y-241947D01*
X68206Y-242281D01*
G01X74510Y-248531D02*
X75143Y-247697D01*
X75460Y-246864D01*
Y-243531D01*
X75143Y-242697D01*
X74510Y-241864D01*
G01X77900Y-245864D02*
X78280Y-246447D01*
X78786Y-246781D01*
X79356Y-246864D01*
X79863Y-246781D01*
X80370Y-246364D01*
X80686Y-245864D01*
X80750Y-245364D01*
X80623Y-244781D01*
X80180Y-244364D01*
X79736Y-244197D01*
X79166D01*
G01X79736D02*
X80116Y-243947D01*
X80433Y-243531D01*
X80560Y-243031D01*
X80433Y-242531D01*
X80116Y-242114D01*
X79546Y-241864D01*
X78976Y-241947D01*
X78406Y-242281D01*
G01X83190Y-242697D02*
X83570Y-242197D01*
X84013Y-241947D01*
X84520Y-241864D01*
X85153Y-242031D01*
X85596Y-242447D01*
X85723Y-242947D01*
X85660Y-243447D01*
X85406Y-243864D01*
X84140Y-244697D01*
X83570Y-245281D01*
X83190Y-246114D01*
X83063Y-246864D01*
X85723D01*
G01X89366D02*
X89493Y-245781D01*
X89683Y-244864D01*
X89936Y-244031D01*
X90253Y-243114D01*
X90760Y-241864D01*
X88226D01*
G01X93770Y-245197D02*
X95416D01*
G01X98490Y-242697D02*
X98870Y-242197D01*
X99313Y-241947D01*
X99820Y-241864D01*
X100453Y-242031D01*
X100896Y-242447D01*
X101023Y-242947D01*
X100960Y-243447D01*
X100706Y-243864D01*
X99440Y-244697D01*
X98870Y-245281D01*
X98490Y-246114D01*
X98363Y-246864D01*
X101023D01*
G01X103400Y-245864D02*
X103780Y-246447D01*
X104286Y-246781D01*
X104856Y-246864D01*
X105363Y-246781D01*
X105870Y-246364D01*
X106186Y-245864D01*
X106250Y-245364D01*
X106123Y-244781D01*
X105680Y-244364D01*
X105236Y-244197D01*
X104666D01*
G01X105236D02*
X105616Y-243947D01*
X105933Y-243531D01*
X106060Y-243031D01*
X105933Y-242531D01*
X105616Y-242114D01*
X105046Y-241864D01*
X104476Y-241947D01*
X103906Y-242281D01*
G01X110653Y-246864D02*
Y-241864D01*
X108310Y-245447D01*
X111476D01*
G01X113600Y-246114D02*
X113980Y-246531D01*
X114423Y-246781D01*
X114993Y-246864D01*
X115563Y-246697D01*
X116006Y-246364D01*
X116323Y-245781D01*
X116386Y-245114D01*
X116260Y-244447D01*
X115943Y-244031D01*
X115500Y-243697D01*
X115056Y-243614D01*
X114613Y-243697D01*
X114043Y-244031D01*
X114233Y-241864D01*
X115943D01*
G01X123990Y-246864D02*
Y-241864D01*
X126396D01*
G01X125510Y-244281D02*
X123990D01*
G01X128710Y-246864D02*
X130293Y-241864D01*
X131876Y-246864D01*
G01X131306Y-245114D02*
X129280D01*
G01X134063Y-246864D02*
X136723Y-241864D01*
G01X134063D02*
X136723Y-246864D01*
G01X140493Y-247031D02*
X140366Y-246947D01*
Y-246781D01*
X140493Y-246697D01*
X140620Y-246781D01*
Y-246947D01*
X140493Y-247031D01*
G01Y-244781D02*
X140366Y-244697D01*
Y-244531D01*
X140493Y-244447D01*
X140620Y-244531D01*
Y-244697D01*
X140493Y-244781D01*
G01X145276Y-248531D02*
X144643Y-247697D01*
X144326Y-246864D01*
Y-243531D01*
X144643Y-242697D01*
X145276Y-241864D01*
G01X150693D02*
X150186Y-242031D01*
X149806Y-242447D01*
X149553Y-242947D01*
X149363Y-243614D01*
X149300Y-244364D01*
X149363Y-245114D01*
X149553Y-245781D01*
X149806Y-246281D01*
X150186Y-246697D01*
X150693Y-246864D01*
X151200Y-246697D01*
X151580Y-246281D01*
X151833Y-245781D01*
X152023Y-245114D01*
X152086Y-244364D01*
X152023Y-243614D01*
X151833Y-242947D01*
X151580Y-242447D01*
X151200Y-242031D01*
X150693Y-241864D01*
G01X154400Y-245864D02*
X154780Y-246447D01*
X155286Y-246781D01*
X155856Y-246864D01*
X156363Y-246781D01*
X156870Y-246364D01*
X157186Y-245864D01*
X157250Y-245364D01*
X157123Y-244781D01*
X156680Y-244364D01*
X156236Y-244197D01*
X155666D01*
G01X156236D02*
X156616Y-243947D01*
X156933Y-243531D01*
X157060Y-243031D01*
X156933Y-242531D01*
X156616Y-242114D01*
X156046Y-241864D01*
X155476Y-241947D01*
X154906Y-242281D01*
G01X161210Y-248531D02*
X161843Y-247697D01*
X162160Y-246864D01*
Y-243531D01*
X161843Y-242697D01*
X161210Y-241864D01*
G01X164600Y-245864D02*
X164980Y-246447D01*
X165486Y-246781D01*
X166056Y-246864D01*
X166563Y-246781D01*
X167070Y-246364D01*
X167386Y-245864D01*
X167450Y-245364D01*
X167323Y-244781D01*
X166880Y-244364D01*
X166436Y-244197D01*
X165866D01*
G01X166436D02*
X166816Y-243947D01*
X167133Y-243531D01*
X167260Y-243031D01*
X167133Y-242531D01*
X166816Y-242114D01*
X166246Y-241864D01*
X165676Y-241947D01*
X165106Y-242281D01*
G01X170016Y-246281D02*
X170460Y-246697D01*
X170966Y-246864D01*
X171473Y-246697D01*
X171916Y-246197D01*
X172233Y-245447D01*
X172360Y-244697D01*
Y-243781D01*
X172233Y-243031D01*
X171916Y-242364D01*
X171536Y-242031D01*
X171093Y-241864D01*
X170586Y-242031D01*
X170206Y-242364D01*
X169953Y-242864D01*
X169826Y-243531D01*
X169953Y-244114D01*
X170270Y-244697D01*
X170650Y-245031D01*
X171093Y-245114D01*
X171600Y-244947D01*
X171980Y-244531D01*
X172360Y-243781D01*
G01X176066Y-246864D02*
X176193Y-245781D01*
X176383Y-244864D01*
X176636Y-244031D01*
X176953Y-243114D01*
X177460Y-241864D01*
X174926D01*
G01X180470Y-245197D02*
X182116D01*
G01X185000Y-245864D02*
X185380Y-246447D01*
X185886Y-246781D01*
X186456Y-246864D01*
X186963Y-246781D01*
X187470Y-246364D01*
X187786Y-245864D01*
X187850Y-245364D01*
X187723Y-244781D01*
X187280Y-244364D01*
X186836Y-244197D01*
X186266D01*
G01X186836D02*
X187216Y-243947D01*
X187533Y-243531D01*
X187660Y-243031D01*
X187533Y-242531D01*
X187216Y-242114D01*
X186646Y-241864D01*
X186076Y-241947D01*
X185506Y-242281D01*
G01X190290Y-244781D02*
X190733Y-244197D01*
X191113Y-243864D01*
X191620Y-243697D01*
X192063Y-243864D01*
X192380Y-244197D01*
X192633Y-244697D01*
X192696Y-245281D01*
X192633Y-245781D01*
X192380Y-246281D01*
X192000Y-246697D01*
X191556Y-246864D01*
X191050Y-246697D01*
X190606Y-246197D01*
X190353Y-245447D01*
X190290Y-244614D01*
X190416Y-243531D01*
X190606Y-242947D01*
X190923Y-242364D01*
X191366Y-241947D01*
X191810Y-241864D01*
X192253Y-242031D01*
X192570Y-242447D01*
G01X196593Y-246864D02*
Y-241864D01*
X195833Y-242864D01*
G01Y-246864D02*
X197353D01*
G01X202453D02*
Y-241864D01*
X200110Y-245447D01*
X203276D01*
G01X26493Y-176864D02*
Y-251864D01*
X526493D01*
Y-176864D01*
X26493D01*
G01X221493D02*
Y-251864D01*
G01Y-226864D02*
X324493D01*
Y-201864D01*
G01X221493D02*
X324493D01*
G01X332000Y-236864D02*
Y-231864D01*
X333266D01*
X333773Y-232114D01*
X334153Y-232447D01*
X334470Y-232947D01*
X334723Y-233531D01*
X334786Y-234364D01*
X334723Y-235197D01*
X334470Y-235781D01*
X334153Y-236281D01*
X333773Y-236614D01*
X333266Y-236864D01*
X332000D01*
G01X336910D02*
X338493Y-231864D01*
X340076Y-236864D01*
G01X339506Y-235114D02*
X337480D01*
G01X343593Y-231864D02*
Y-236864D01*
G01X342136Y-231864D02*
X345050D01*
G01X349960Y-236864D02*
X347426D01*
Y-231864D01*
X349960D01*
G01X348946Y-234281D02*
X347426D01*
G01X353793Y-237031D02*
X353666Y-236947D01*
Y-236781D01*
X353793Y-236697D01*
X353920Y-236781D01*
Y-236947D01*
X353793Y-237031D01*
G01Y-234781D02*
X353666Y-234697D01*
Y-234531D01*
X353793Y-234447D01*
X353920Y-234531D01*
Y-234697D01*
X353793Y-234781D01*
G01X326493Y-176864D02*
Y-251864D01*
G01X324493Y-176864D02*
Y-251864D01*
G01X326493Y-226864D02*
X526493D01*
G01X332126Y-211864D02*
Y-206864D01*
X333646D01*
X334153Y-207114D01*
X334533Y-207697D01*
X334660Y-208364D01*
X334533Y-209031D01*
X334216Y-209531D01*
X333646Y-209781D01*
X332126D01*
G01X337353Y-212031D02*
X339633Y-206864D01*
G01X342136Y-211864D02*
Y-206864D01*
X345050Y-211864D01*
Y-206864D01*
G01X348693Y-212031D02*
X348566Y-211947D01*
Y-211781D01*
X348693Y-211697D01*
X348820Y-211781D01*
Y-211947D01*
X348693Y-212031D01*
G01Y-209781D02*
X348566Y-209697D01*
Y-209531D01*
X348693Y-209447D01*
X348820Y-209531D01*
Y-209697D01*
X348693Y-209781D01*
G01X326493Y-201864D02*
X526493D01*
G01X332126Y-186864D02*
Y-181864D01*
X333646D01*
X334153Y-182114D01*
X334533Y-182697D01*
X334660Y-183364D01*
X334533Y-184031D01*
X334216Y-184531D01*
X333646Y-184781D01*
X332126D01*
G01X337226Y-186864D02*
Y-181864D01*
X338810D01*
X339316Y-182114D01*
X339633Y-182447D01*
X339760Y-183114D01*
X339633Y-183781D01*
X339253Y-184197D01*
X338810Y-184447D01*
X337226D01*
G01X338810D02*
X339760Y-186864D01*
G01X343593D02*
X343086Y-186781D01*
X342643Y-186447D01*
X342263Y-185947D01*
X342010Y-185364D01*
X341883Y-184697D01*
Y-184031D01*
X342010Y-183364D01*
X342263Y-182781D01*
X342643Y-182281D01*
X343086Y-181947D01*
X343593Y-181864D01*
X344100Y-181947D01*
X344543Y-182281D01*
X344923Y-182781D01*
X345176Y-183364D01*
X345303Y-184031D01*
Y-184697D01*
X345176Y-185364D01*
X344923Y-185947D01*
X344543Y-186447D01*
X344100Y-186781D01*
X343593Y-186864D01*
G01X347426Y-185864D02*
X347743Y-186364D01*
X348123Y-186697D01*
X348566Y-186864D01*
X349073Y-186697D01*
X349453Y-186364D01*
X349833Y-185864D01*
X349960Y-185197D01*
Y-181864D01*
G01X355060Y-186864D02*
X352526D01*
Y-181864D01*
X355060D01*
G01X354046Y-184281D02*
X352526D01*
G01X360286Y-182281D02*
X359906Y-182031D01*
X359463Y-181864D01*
X358956D01*
X358386Y-182114D01*
X357943Y-182531D01*
X357626Y-183031D01*
X357373Y-183864D01*
X357310Y-184614D01*
X357436Y-185364D01*
X357626Y-185864D01*
X358006Y-186364D01*
X358450Y-186697D01*
X358893Y-186864D01*
X359336D01*
X359780Y-186697D01*
X360160Y-186447D01*
X360476Y-186114D01*
G01X363993Y-181864D02*
Y-186864D01*
G01X362536Y-181864D02*
X365450D01*
G01X369093Y-187031D02*
X368966Y-186947D01*
Y-186781D01*
X369093Y-186697D01*
X369220Y-186781D01*
Y-186947D01*
X369093Y-187031D01*
G01Y-184781D02*
X368966Y-184697D01*
Y-184531D01*
X369093Y-184447D01*
X369220Y-184531D01*
Y-184697D01*
X369093Y-184781D01*
G01X447126Y-236864D02*
Y-231864D01*
X448710D01*
X449216Y-232114D01*
X449533Y-232447D01*
X449660Y-233114D01*
X449533Y-233781D01*
X449153Y-234197D01*
X448710Y-234447D01*
X447126D01*
G01X448710D02*
X449660Y-236864D01*
G01X454760D02*
X452226D01*
Y-231864D01*
X454760D01*
G01X453746Y-234281D02*
X452226D01*
G01X457010Y-231864D02*
X458593Y-236864D01*
X460176Y-231864D01*
G01X463693Y-237031D02*
X463566Y-236947D01*
Y-236781D01*
X463693Y-236697D01*
X463820Y-236781D01*
Y-236947D01*
X463693Y-237031D01*
G01Y-234781D02*
X463566Y-234697D01*
Y-234531D01*
X463693Y-234447D01*
X463820Y-234531D01*
Y-234697D01*
X463693Y-234781D01*
G01X441493Y-226864D02*
Y-251864D01*
G01X490493Y-226864D02*
Y-251864D01*
G01X-1043962Y-705877D02*
Y2342823D01*
X2300638D01*
Y-705877D01*
X-1043962D01*
G01X37198Y-238524D02*
X37825Y-239049D01*
X38530Y-239364D01*
X39156D01*
X39783Y-239049D01*
X40253Y-238524D01*
X40488Y-237789D01*
X40331Y-237054D01*
X39940Y-236424D01*
X39235Y-236004D01*
X38295Y-235794D01*
X37746Y-235374D01*
X37511Y-234639D01*
X37668Y-233904D01*
X38060Y-233379D01*
X38608Y-233064D01*
X39156D01*
X39705Y-233274D01*
X40175Y-233799D01*
G01X43498Y-239364D02*
Y-233064D01*
G01X46788D02*
Y-239364D01*
G01Y-236214D02*
X43498D01*
G01X50503Y-233064D02*
X52383D01*
G01X51443D02*
Y-239364D01*
G01X50503D02*
X52383D01*
G01X59310D02*
X56176D01*
Y-233064D01*
X59310D01*
G01X58056Y-236109D02*
X56176D01*
G01X62241Y-239364D02*
Y-233064D01*
X65845Y-239364D01*
Y-233064D01*
G01X70186Y-240519D02*
X70500Y-239154D01*
G01X76643Y-233064D02*
Y-239364D01*
G01X74841Y-233064D02*
X78445D01*
G01X80985Y-239364D02*
X82943Y-233064D01*
X84901Y-239364D01*
G01X84196Y-237159D02*
X81690D01*
G01X88303Y-233064D02*
X90183D01*
G01X89243D02*
Y-239364D01*
G01X88303D02*
X90183D01*
G01X93193Y-233064D02*
X94290Y-239364D01*
X95543Y-233064D01*
X96796Y-239364D01*
X97893Y-233064D01*
G01X99885Y-239364D02*
X101843Y-233064D01*
X103801Y-239364D01*
G01X103096Y-237159D02*
X100590D01*
G01X106341Y-239364D02*
Y-233064D01*
X109945Y-239364D01*
Y-233064D01*
G01X119176Y-239364D02*
Y-233064D01*
X121135D01*
X121761Y-233379D01*
X122153Y-233799D01*
X122310Y-234639D01*
X122153Y-235479D01*
X121683Y-236004D01*
X121135Y-236319D01*
X119176D01*
G01X121135D02*
X122310Y-239364D01*
G01X127043Y-239574D02*
X126886Y-239469D01*
Y-239259D01*
X127043Y-239154D01*
X127200Y-239259D01*
Y-239469D01*
X127043Y-239574D01*
G01X133343Y-239364D02*
X132716Y-239259D01*
X132168Y-238839D01*
X131698Y-238209D01*
X131385Y-237474D01*
X131228Y-236634D01*
Y-235794D01*
X131385Y-234954D01*
X131698Y-234219D01*
X132168Y-233589D01*
X132716Y-233169D01*
X133343Y-233064D01*
X133970Y-233169D01*
X134518Y-233589D01*
X134988Y-234219D01*
X135301Y-234954D01*
X135458Y-235794D01*
Y-236634D01*
X135301Y-237474D01*
X134988Y-238209D01*
X134518Y-238839D01*
X133970Y-239259D01*
X133343Y-239364D01*
G01X139643Y-239574D02*
X139486Y-239469D01*
Y-239259D01*
X139643Y-239154D01*
X139800Y-239259D01*
Y-239469D01*
X139643Y-239574D01*
G01X147666Y-233589D02*
X147196Y-233274D01*
X146648Y-233064D01*
X146021D01*
X145316Y-233379D01*
X144768Y-233904D01*
X144376Y-234534D01*
X144063Y-235584D01*
X143985Y-236529D01*
X144141Y-237474D01*
X144376Y-238104D01*
X144846Y-238734D01*
X145395Y-239154D01*
X145943Y-239364D01*
X146491D01*
X147040Y-239154D01*
X147510Y-238839D01*
X147901Y-238419D01*
G01X152243Y-239574D02*
X152086Y-239469D01*
Y-239259D01*
X152243Y-239154D01*
X152400Y-239259D01*
Y-239469D01*
X152243Y-239574D01*
G01X37120Y-229364D02*
Y-223064D01*
G01X40096D02*
X37120Y-226949D01*
G01X40566Y-229364D02*
X38451Y-225164D01*
G01X43420Y-223064D02*
Y-227579D01*
X43733Y-228524D01*
X44360Y-229154D01*
X45143Y-229364D01*
X45926Y-229154D01*
X46553Y-228524D01*
X46866Y-227579D01*
Y-223064D01*
G01X53010Y-229364D02*
X49876D01*
Y-223064D01*
X53010D01*
G01X51756Y-226109D02*
X49876D01*
G01X56803Y-223064D02*
X58683D01*
G01X57743D02*
Y-229364D01*
G01X56803D02*
X58683D01*
G01X68698Y-228524D02*
X69325Y-229049D01*
X70030Y-229364D01*
X70656D01*
X71283Y-229049D01*
X71753Y-228524D01*
X71988Y-227789D01*
X71831Y-227054D01*
X71440Y-226424D01*
X70735Y-226004D01*
X69795Y-225794D01*
X69246Y-225374D01*
X69011Y-224639D01*
X69168Y-223904D01*
X69560Y-223379D01*
X70108Y-223064D01*
X70656D01*
X71205Y-223274D01*
X71675Y-223799D01*
G01X74998Y-229364D02*
Y-223064D01*
G01X78288D02*
Y-229364D01*
G01Y-226214D02*
X74998D01*
G01X80985Y-229364D02*
X82943Y-223064D01*
X84901Y-229364D01*
G01X84196Y-227159D02*
X81690D01*
G01X87441Y-229364D02*
Y-223064D01*
X91045Y-229364D01*
Y-223064D01*
G01X100198Y-229364D02*
Y-223064D01*
G01X103488D02*
Y-229364D01*
G01Y-226214D02*
X100198D01*
G01X106498Y-228524D02*
X107125Y-229049D01*
X107830Y-229364D01*
X108456D01*
X109083Y-229049D01*
X109553Y-228524D01*
X109788Y-227789D01*
X109631Y-227054D01*
X109240Y-226424D01*
X108535Y-226004D01*
X107595Y-225794D01*
X107046Y-225374D01*
X106811Y-224639D01*
X106968Y-223904D01*
X107360Y-223379D01*
X107908Y-223064D01*
X108456D01*
X109005Y-223274D01*
X109475Y-223799D01*
G01X113503Y-223064D02*
X115383D01*
G01X114443D02*
Y-229364D01*
G01X113503D02*
X115383D01*
G01X118785D02*
X120743Y-223064D01*
X122701Y-229364D01*
G01X121996Y-227159D02*
X119490D01*
G01X125241Y-229364D02*
Y-223064D01*
X128845Y-229364D01*
Y-223064D01*
G01X133813Y-226214D02*
X135380D01*
Y-228104D01*
X134910Y-228734D01*
X134361Y-229154D01*
X133578Y-229364D01*
X132795Y-229154D01*
X132246Y-228734D01*
X131776Y-228104D01*
X131463Y-227369D01*
X131306Y-226529D01*
Y-225794D01*
X131463Y-225164D01*
X131776Y-224429D01*
X132246Y-223799D01*
X132716Y-223379D01*
X133343Y-223064D01*
X133891D01*
X134518Y-223274D01*
X134988Y-223694D01*
G01X139486Y-230519D02*
X139800Y-229154D01*
G01X145943Y-223064D02*
Y-229364D01*
G01X144141Y-223064D02*
X147745D01*
G01X150285Y-229364D02*
X152243Y-223064D01*
X154201Y-229364D01*
G01X153496Y-227159D02*
X150990D01*
G01X158543Y-229364D02*
X157916Y-229259D01*
X157368Y-228839D01*
X156898Y-228209D01*
X156585Y-227474D01*
X156428Y-226634D01*
Y-225794D01*
X156585Y-224954D01*
X156898Y-224219D01*
X157368Y-223589D01*
X157916Y-223169D01*
X158543Y-223064D01*
X159170Y-223169D01*
X159718Y-223589D01*
X160188Y-224219D01*
X160501Y-224954D01*
X160658Y-225794D01*
Y-226634D01*
X160501Y-227474D01*
X160188Y-228209D01*
X159718Y-228839D01*
X159170Y-229259D01*
X158543Y-229364D01*
G01X171143D02*
Y-226529D01*
X169576Y-223064D01*
G01X172710D02*
X171143Y-226529D01*
G01X175720Y-223064D02*
Y-227579D01*
X176033Y-228524D01*
X176660Y-229154D01*
X177443Y-229364D01*
X178226Y-229154D01*
X178853Y-228524D01*
X179166Y-227579D01*
Y-223064D01*
G01X181785Y-229364D02*
X183743Y-223064D01*
X185701Y-229364D01*
G01X184996Y-227159D02*
X182490D01*
G01X188241Y-229364D02*
Y-223064D01*
X191845Y-229364D01*
Y-223064D01*
G01X37041Y-219364D02*
Y-213064D01*
X40645Y-219364D01*
Y-213064D01*
G01X45143Y-219364D02*
X44516Y-219259D01*
X43968Y-218839D01*
X43498Y-218209D01*
X43185Y-217474D01*
X43028Y-216634D01*
Y-215794D01*
X43185Y-214954D01*
X43498Y-214219D01*
X43968Y-213589D01*
X44516Y-213169D01*
X45143Y-213064D01*
X45770Y-213169D01*
X46318Y-213589D01*
X46788Y-214219D01*
X47101Y-214954D01*
X47258Y-215794D01*
Y-216634D01*
X47101Y-217474D01*
X46788Y-218209D01*
X46318Y-218839D01*
X45770Y-219259D01*
X45143Y-219364D01*
G01X51443Y-219574D02*
X51286Y-219469D01*
Y-219259D01*
X51443Y-219154D01*
X51600Y-219259D01*
Y-219469D01*
X51443Y-219574D01*
G01X57743Y-219364D02*
Y-213064D01*
X56803Y-214324D01*
G01Y-219364D02*
X58683D01*
G01X64043D02*
X64591Y-219259D01*
X65218Y-218944D01*
X65610Y-218419D01*
X65766Y-217684D01*
X65610Y-216949D01*
X65140Y-216319D01*
X64435Y-216004D01*
X63651D01*
X63181Y-215794D01*
X62790Y-215269D01*
X62633Y-214534D01*
X62868Y-213799D01*
X63416Y-213274D01*
X64043Y-213064D01*
X64670Y-213274D01*
X65218Y-213799D01*
X65453Y-214534D01*
X65296Y-215269D01*
X64905Y-215794D01*
X64435Y-216004D01*
X63651D01*
X62946Y-216319D01*
X62476Y-216949D01*
X62320Y-217684D01*
X62476Y-218419D01*
X62868Y-218944D01*
X63495Y-219259D01*
X64043Y-219364D01*
G01X70343D02*
X70891Y-219259D01*
X71518Y-218944D01*
X71910Y-218419D01*
X72066Y-217684D01*
X71910Y-216949D01*
X71440Y-216319D01*
X70735Y-216004D01*
X69951D01*
X69481Y-215794D01*
X69090Y-215269D01*
X68933Y-214534D01*
X69168Y-213799D01*
X69716Y-213274D01*
X70343Y-213064D01*
X70970Y-213274D01*
X71518Y-213799D01*
X71753Y-214534D01*
X71596Y-215269D01*
X71205Y-215794D01*
X70735Y-216004D01*
X69951D01*
X69246Y-216319D01*
X68776Y-216949D01*
X68620Y-217684D01*
X68776Y-218419D01*
X69168Y-218944D01*
X69795Y-219259D01*
X70343Y-219364D01*
G01X76486Y-220519D02*
X76800Y-219154D01*
G01X80593Y-213064D02*
X81690Y-219364D01*
X82943Y-213064D01*
X84196Y-219364D01*
X85293Y-213064D01*
G01X90810Y-219364D02*
X87676D01*
Y-213064D01*
X90810D01*
G01X89556Y-216109D02*
X87676D01*
G01X93741Y-219364D02*
Y-213064D01*
X97345Y-219364D01*
Y-213064D01*
G01X106498Y-219364D02*
Y-213064D01*
G01X109788D02*
Y-219364D01*
G01Y-216214D02*
X106498D01*
G01X112093Y-213064D02*
X113190Y-219364D01*
X114443Y-213064D01*
X115696Y-219364D01*
X116793Y-213064D01*
G01X118785Y-219364D02*
X120743Y-213064D01*
X122701Y-219364D01*
G01X121996Y-217159D02*
X119490D01*
G01X131855Y-214114D02*
X132325Y-213484D01*
X132873Y-213169D01*
X133500Y-213064D01*
X134283Y-213274D01*
X134831Y-213799D01*
X134988Y-214429D01*
X134910Y-215059D01*
X134596Y-215584D01*
X133030Y-216634D01*
X132325Y-217369D01*
X131855Y-218419D01*
X131698Y-219364D01*
X134988D01*
G01X137841D02*
Y-213064D01*
X141445Y-219364D01*
Y-213064D01*
G01X144220Y-219364D02*
Y-213064D01*
X145786D01*
X146413Y-213379D01*
X146883Y-213799D01*
X147275Y-214429D01*
X147588Y-215164D01*
X147666Y-216214D01*
X147588Y-217264D01*
X147275Y-217999D01*
X146883Y-218629D01*
X146413Y-219049D01*
X145786Y-219364D01*
X144220D01*
G01X156976D02*
Y-213064D01*
X158935D01*
X159561Y-213379D01*
X159953Y-213799D01*
X160110Y-214639D01*
X159953Y-215479D01*
X159483Y-216004D01*
X158935Y-216319D01*
X156976D01*
G01X158935D02*
X160110Y-219364D01*
G01X163120D02*
Y-213064D01*
X164686D01*
X165313Y-213379D01*
X165783Y-213799D01*
X166175Y-214429D01*
X166488Y-215164D01*
X166566Y-216214D01*
X166488Y-217264D01*
X166175Y-217999D01*
X165783Y-218629D01*
X165313Y-219049D01*
X164686Y-219364D01*
X163120D01*
G01X171143Y-219574D02*
X170986Y-219469D01*
Y-219259D01*
X171143Y-219154D01*
X171300Y-219259D01*
Y-219469D01*
X171143Y-219574D01*
G01X61143Y-206664D02*
X58623Y-206247D01*
X56418Y-204581D01*
X54528Y-202081D01*
X53268Y-199164D01*
X52638Y-195831D01*
Y-192497D01*
X53268Y-189164D01*
X54528Y-186247D01*
X56418Y-183748D01*
X58623Y-182081D01*
X61143Y-181664D01*
X63663Y-182081D01*
X65868Y-183748D01*
X67758Y-186247D01*
X69018Y-189164D01*
X69648Y-192497D01*
Y-195831D01*
X69018Y-199164D01*
X67758Y-202081D01*
X65868Y-204581D01*
X63663Y-206247D01*
X61143Y-206664D01*
G01X63663Y-199997D02*
X67443Y-206664D01*
G01X80988Y-189998D02*
Y-201664D01*
X82248Y-204581D01*
X84138Y-206247D01*
X86343Y-206664D01*
X88548Y-206247D01*
X90438Y-204581D01*
X91698Y-201664D01*
G01Y-206664D02*
Y-189998D01*
G01X117213Y-206664D02*
Y-189998D01*
G01Y-192914D02*
X115953Y-191248D01*
X114063Y-190414D01*
X111858Y-189998D01*
X109653Y-190831D01*
X107763Y-192497D01*
X106503Y-194998D01*
X105873Y-198331D01*
X106503Y-201664D01*
X107763Y-204165D01*
X109653Y-205831D01*
X111858Y-206664D01*
X114063Y-206247D01*
X115953Y-204998D01*
X117213Y-203331D01*
G01X131388Y-206664D02*
Y-189998D01*
G01Y-194164D02*
X132648Y-192081D01*
X134538Y-190414D01*
X137058Y-189998D01*
X139263Y-190414D01*
X141153Y-192081D01*
X142098Y-194998D01*
Y-206664D01*
G01X161943Y-181664D02*
Y-206664D01*
G01X157533Y-189998D02*
X166353D01*
G01X192813Y-206664D02*
Y-189998D01*
G01Y-192914D02*
X191553Y-191248D01*
X189663Y-190414D01*
X187458Y-189998D01*
X185253Y-190831D01*
X183363Y-192497D01*
X182103Y-194998D01*
X181473Y-198331D01*
X182103Y-201664D01*
X183363Y-204165D01*
X185253Y-205831D01*
X187458Y-206664D01*
X189663Y-206247D01*
X191553Y-204998D01*
X192813Y-203331D01*
G01X232493Y-186364D02*
Y-194364D01*
X236493D01*
G01X244293D02*
Y-189031D01*
G01Y-189964D02*
X243893Y-189431D01*
X243293Y-189164D01*
X242593Y-189031D01*
X241893Y-189297D01*
X241293Y-189831D01*
X240893Y-190631D01*
X240693Y-191697D01*
X240893Y-192764D01*
X241293Y-193564D01*
X241893Y-194097D01*
X242593Y-194364D01*
X243293Y-194231D01*
X243893Y-193831D01*
X244293Y-193298D01*
G01X248393Y-196764D02*
X248993Y-197031D01*
X249793Y-196764D01*
X250293Y-196231D01*
X250693Y-195564D01*
X251293Y-193431D01*
X252593Y-189031D01*
G01X249393D02*
X251293Y-193431D01*
G01X256993Y-190764D02*
X260193D01*
X259893Y-189831D01*
X259393Y-189297D01*
X258693Y-189031D01*
X257993Y-189164D01*
X257393Y-189564D01*
X256993Y-190497D01*
X256793Y-191298D01*
Y-192097D01*
X256993Y-192897D01*
X257493Y-193697D01*
X258093Y-194231D01*
X258793Y-194364D01*
X259493Y-194097D01*
X260193Y-193298D01*
G01X265093Y-194364D02*
Y-189031D01*
G01Y-190097D02*
X265593Y-189564D01*
X266093Y-189164D01*
X266793Y-189031D01*
X267293Y-189164D01*
X267893Y-189564D01*
G01X254793Y-236364D02*
X257193D01*
G01X255993D02*
Y-244364D01*
G01X254793D02*
X257193D01*
G01X262593D02*
Y-239031D01*
G01Y-240097D02*
X263093Y-239564D01*
X263593Y-239164D01*
X264293Y-239031D01*
X264793Y-239164D01*
X265393Y-239564D01*
G01X270493Y-240764D02*
X273693D01*
X273393Y-239831D01*
X272893Y-239297D01*
X272193Y-239031D01*
X271493Y-239164D01*
X270893Y-239564D01*
X270493Y-240497D01*
X270293Y-241298D01*
Y-242097D01*
X270493Y-242897D01*
X270993Y-243697D01*
X271593Y-244231D01*
X272293Y-244364D01*
X272993Y-244097D01*
X273693Y-243298D01*
G01X278293Y-244364D02*
Y-239031D01*
G01Y-240364D02*
X278693Y-239697D01*
X279293Y-239164D01*
X280093Y-239031D01*
X280793Y-239164D01*
X281393Y-239697D01*
X281693Y-240631D01*
Y-244364D01*
G01X286493Y-240764D02*
X289693D01*
X289393Y-239831D01*
X288893Y-239297D01*
X288193Y-239031D01*
X287493Y-239164D01*
X286893Y-239564D01*
X286493Y-240497D01*
X286293Y-241298D01*
Y-242097D01*
X286493Y-242897D01*
X286993Y-243697D01*
X287593Y-244231D01*
X288293Y-244364D01*
X288993Y-244097D01*
X289693Y-243298D01*
G01X263493Y-211364D02*
X265993Y-219364D01*
X268493Y-211364D01*
G01X276193Y-212031D02*
X275593Y-211631D01*
X274893Y-211364D01*
X274093D01*
X273193Y-211764D01*
X272493Y-212431D01*
X271993Y-213231D01*
X271593Y-214564D01*
X271493Y-215764D01*
X271693Y-216964D01*
X271993Y-217764D01*
X272593Y-218564D01*
X273293Y-219097D01*
X273993Y-219364D01*
X274693D01*
X275393Y-219097D01*
X275993Y-218697D01*
X276493Y-218164D01*
G01X284193Y-212031D02*
X283593Y-211631D01*
X282893Y-211364D01*
X282093D01*
X281193Y-211764D01*
X280493Y-212431D01*
X279993Y-213231D01*
X279593Y-214564D01*
X279493Y-215764D01*
X279693Y-216964D01*
X279993Y-217764D01*
X280593Y-218564D01*
X281293Y-219097D01*
X281993Y-219364D01*
X282693D01*
X283393Y-219097D01*
X283993Y-218697D01*
X284493Y-218164D01*
G01X288093Y-212697D02*
X288693Y-211897D01*
X289393Y-211497D01*
X290193Y-211364D01*
X291193Y-211631D01*
X291893Y-212297D01*
X292093Y-213097D01*
X291993Y-213898D01*
X291593Y-214564D01*
X289593Y-215897D01*
X288693Y-216831D01*
X288093Y-218164D01*
X287893Y-219364D01*
X292093D01*
G01X283793Y-193164D02*
X284393Y-193831D01*
X285093Y-194231D01*
X285993Y-194364D01*
X286893Y-194097D01*
X287593Y-193564D01*
X288093Y-192631D01*
X288193Y-191564D01*
X287993Y-190497D01*
X287493Y-189831D01*
X286793Y-189297D01*
X286093Y-189164D01*
X285393Y-189297D01*
X284493Y-189831D01*
X284793Y-186364D01*
X287493D01*
G01X359093Y-237697D02*
X359693Y-236897D01*
X360393Y-236497D01*
X361193Y-236364D01*
X362193Y-236631D01*
X362893Y-237297D01*
X363093Y-238097D01*
X362993Y-238898D01*
X362593Y-239564D01*
X360593Y-240897D01*
X359693Y-241831D01*
X359093Y-243164D01*
X358893Y-244364D01*
X363093D01*
G01X368993Y-236364D02*
X368193Y-236631D01*
X367593Y-237297D01*
X367193Y-238097D01*
X366893Y-239164D01*
X366793Y-240364D01*
X366893Y-241564D01*
X367193Y-242631D01*
X367593Y-243431D01*
X368193Y-244097D01*
X368993Y-244364D01*
X369793Y-244097D01*
X370393Y-243431D01*
X370793Y-242631D01*
X371093Y-241564D01*
X371193Y-240364D01*
X371093Y-239164D01*
X370793Y-238097D01*
X370393Y-237297D01*
X369793Y-236631D01*
X368993Y-236364D01*
G01X376993Y-244364D02*
Y-236364D01*
X375793Y-237964D01*
G01Y-244364D02*
X378193D01*
G01X383093Y-237697D02*
X383693Y-236897D01*
X384393Y-236497D01*
X385193Y-236364D01*
X386193Y-236631D01*
X386893Y-237297D01*
X387093Y-238097D01*
X386993Y-238898D01*
X386593Y-239564D01*
X384593Y-240897D01*
X383693Y-241831D01*
X383093Y-243164D01*
X382893Y-244364D01*
X387093D01*
G01X391193Y-244631D02*
X394793Y-236364D01*
G01X400993Y-244364D02*
Y-236364D01*
X399793Y-237964D01*
G01Y-244364D02*
X402193D01*
G01X408993Y-236364D02*
X408193Y-236631D01*
X407593Y-237297D01*
X407193Y-238097D01*
X406893Y-239164D01*
X406793Y-240364D01*
X406893Y-241564D01*
X407193Y-242631D01*
X407593Y-243431D01*
X408193Y-244097D01*
X408993Y-244364D01*
X409793Y-244097D01*
X410393Y-243431D01*
X410793Y-242631D01*
X411093Y-241564D01*
X411193Y-240364D01*
X411093Y-239164D01*
X410793Y-238097D01*
X410393Y-237297D01*
X409793Y-236631D01*
X408993Y-236364D01*
G01X415193Y-244631D02*
X418793Y-236364D01*
G01X422793Y-242764D02*
X423393Y-243697D01*
X424193Y-244231D01*
X425093Y-244364D01*
X425893Y-244231D01*
X426693Y-243564D01*
X427193Y-242764D01*
X427293Y-241964D01*
X427093Y-241031D01*
X426393Y-240364D01*
X425693Y-240097D01*
X424793D01*
G01X425693D02*
X426293Y-239697D01*
X426793Y-239031D01*
X426993Y-238231D01*
X426793Y-237431D01*
X426293Y-236764D01*
X425393Y-236364D01*
X424493Y-236497D01*
X423593Y-237031D01*
G01X432993Y-244364D02*
Y-236364D01*
X431793Y-237964D01*
G01Y-244364D02*
X434193D01*
G01X358793Y-219364D02*
Y-211364D01*
X360793D01*
X361593Y-211764D01*
X362193Y-212297D01*
X362693Y-213097D01*
X363093Y-214031D01*
X363193Y-215364D01*
X363093Y-216697D01*
X362693Y-217631D01*
X362193Y-218431D01*
X361593Y-218964D01*
X360793Y-219364D01*
X358793D01*
G01X366493D02*
X368993Y-211364D01*
X371493Y-219364D01*
G01X370593Y-216564D02*
X367393D01*
G01X376993Y-211364D02*
Y-219364D01*
G01X374693Y-211364D02*
X379293D01*
G01X383093Y-216031D02*
X383793Y-215097D01*
X384393Y-214564D01*
X385193Y-214297D01*
X385893Y-214564D01*
X386393Y-215097D01*
X386793Y-215897D01*
X386893Y-216831D01*
X386793Y-217631D01*
X386393Y-218431D01*
X385793Y-219097D01*
X385093Y-219364D01*
X384293Y-219097D01*
X383593Y-218298D01*
X383193Y-217097D01*
X383093Y-215764D01*
X383293Y-214031D01*
X383593Y-213097D01*
X384093Y-212164D01*
X384793Y-211497D01*
X385493Y-211364D01*
X386193Y-211631D01*
X386693Y-212297D01*
G01X390393Y-219364D02*
Y-211364D01*
X392993Y-218031D01*
X395593Y-211364D01*
Y-219364D01*
G01X400993Y-211364D02*
Y-219364D01*
G01X398693Y-211364D02*
X403293D01*
G01X406893Y-219364D02*
Y-211364D01*
G01X411093D02*
Y-219364D01*
G01Y-215364D02*
X406893D01*
G01X414793Y-217764D02*
X415393Y-218697D01*
X416193Y-219231D01*
X417093Y-219364D01*
X417893Y-219231D01*
X418693Y-218564D01*
X419193Y-217764D01*
X419293Y-216964D01*
X419093Y-216031D01*
X418393Y-215364D01*
X417693Y-215097D01*
X416793D01*
G01X417693D02*
X418293Y-214697D01*
X418793Y-214031D01*
X418993Y-213231D01*
X418793Y-212431D01*
X418293Y-211764D01*
X417393Y-211364D01*
X416493Y-211497D01*
X415593Y-212031D01*
G01X422493Y-219364D02*
X424993Y-211364D01*
X427493Y-219364D01*
G01X426593Y-216564D02*
X423393D01*
G01X430793Y-219364D02*
Y-211364D01*
X432793D01*
X433593Y-211764D01*
X434193Y-212297D01*
X434693Y-213097D01*
X435093Y-214031D01*
X435193Y-215364D01*
X435093Y-216697D01*
X434693Y-217631D01*
X434193Y-218431D01*
X433593Y-218964D01*
X432793Y-219364D01*
X430793D01*
G01X440993Y-211364D02*
X440193Y-211631D01*
X439593Y-212297D01*
X439193Y-213097D01*
X438893Y-214164D01*
X438793Y-215364D01*
X438893Y-216564D01*
X439193Y-217631D01*
X439593Y-218431D01*
X440193Y-219097D01*
X440993Y-219364D01*
X441793Y-219097D01*
X442393Y-218431D01*
X442793Y-217631D01*
X443093Y-216564D01*
X443193Y-215364D01*
X443093Y-214164D01*
X442793Y-213097D01*
X442393Y-212297D01*
X441793Y-211631D01*
X440993Y-211364D01*
G01X380993Y-186364D02*
Y-194364D01*
G01X378693Y-186364D02*
X383293D01*
G01X387093Y-191031D02*
X387793Y-190097D01*
X388393Y-189564D01*
X389193Y-189297D01*
X389893Y-189564D01*
X390393Y-190097D01*
X390793Y-190897D01*
X390893Y-191831D01*
X390793Y-192631D01*
X390393Y-193431D01*
X389793Y-194097D01*
X389093Y-194364D01*
X388293Y-194097D01*
X387593Y-193298D01*
X387193Y-192097D01*
X387093Y-190764D01*
X387293Y-189031D01*
X387593Y-188097D01*
X388093Y-187164D01*
X388793Y-186497D01*
X389493Y-186364D01*
X390193Y-186631D01*
X390693Y-187297D01*
G01X394393Y-194364D02*
Y-186364D01*
X396993Y-193031D01*
X399593Y-186364D01*
Y-194364D01*
G01X401993Y-197031D02*
X407993D01*
G01X415193Y-187031D02*
X414593Y-186631D01*
X413893Y-186364D01*
X413093D01*
X412193Y-186764D01*
X411493Y-187431D01*
X410993Y-188231D01*
X410593Y-189564D01*
X410493Y-190764D01*
X410693Y-191964D01*
X410993Y-192764D01*
X411593Y-193564D01*
X412293Y-194097D01*
X412993Y-194364D01*
X413693D01*
X414393Y-194097D01*
X414993Y-193697D01*
X415493Y-193164D01*
G01X418393Y-194364D02*
Y-186364D01*
X420993Y-193031D01*
X423593Y-186364D01*
Y-194364D01*
G01X425993Y-197031D02*
X431993D01*
G01X434793Y-194364D02*
Y-186364D01*
X436793D01*
X437593Y-186764D01*
X438193Y-187297D01*
X438693Y-188097D01*
X439093Y-189031D01*
X439193Y-190364D01*
X439093Y-191697D01*
X438693Y-192631D01*
X438193Y-193431D01*
X437593Y-193964D01*
X436793Y-194364D01*
X434793D01*
G01X473793Y-244364D02*
Y-236364D01*
X475793D01*
X476593Y-236764D01*
X477193Y-237297D01*
X477693Y-238097D01*
X478093Y-239031D01*
X478193Y-240364D01*
X478093Y-241697D01*
X477693Y-242631D01*
X477193Y-243431D01*
X476593Y-243964D01*
X475793Y-244364D01*
X473793D01*
G01X503493D02*
Y-236364D01*
X502293Y-237964D01*
G01Y-244364D02*
X504693D01*
G01X509593Y-241031D02*
X510293Y-240097D01*
X510893Y-239564D01*
X511693Y-239297D01*
X512393Y-239564D01*
X512893Y-240097D01*
X513293Y-240897D01*
X513393Y-241831D01*
X513293Y-242631D01*
X512893Y-243431D01*
X512293Y-244097D01*
X511593Y-244364D01*
X510793Y-244097D01*
X510093Y-243298D01*
X509693Y-242097D01*
X509593Y-240764D01*
X509793Y-239031D01*
X510093Y-238097D01*
X510593Y-237164D01*
X511293Y-236497D01*
X511993Y-236364D01*
X512693Y-236631D01*
X513193Y-237297D01*
M02*
